G04 CAM350 V10.2.1 (Build 391) Date:  Fri Dec 11 17:20:18 2015 *
G04 Database: (Untitled) *
G04 Layer 5: TMASK.art *
%FSLAX35Y35*%
%MOIN*%
%SFA1.000B1.000*%

%MIA0B0*%
%IPPOS*%
%AMMACRO18*
4,1,40,0.00700,0.01100,-0.00700,0.01100,-0.00769,0.01094,-0.00837,0.01076,-0.00900,0.01046,-0.00957,0.01006,-0.01006,0.00957,-0.01046,0.00900,-0.01076,0.00837,-0.01094,0.00770,-0.01100,0.00700,-0.01100,-0.00700,-0.01094,-0.00769,-0.01076,-0.00837,-0.01046,-0.00900,-0.01006,-0.00957,-0.00957,-0.01006,-0.00900,-0.01046,-0.00837,-0.01076,-0.00769,-0.01094,-0.00700,-0.01100,0.00700,-0.01100,0.00770,-0.01094,0.00837,-0.01076,0.00900,-0.01046,0.00957,-0.01006,0.01006,-0.00957,0.01046,-0.00900,0.01076,-0.00837,0.01094,-0.00769,0.01100,-0.00700,0.01100,0.00700,0.01094,0.00770,0.01076,0.00837,0.01046,0.00900,0.01006,0.00957,0.00957,0.01006,0.00900,0.01046,0.00837,0.01076,0.00770,0.01094,0.00700,0.01100,0.00000*
%
%AMMACRO26*
4,1,40,0.00700,0.01100,-0.00700,0.01100,-0.00769,0.01094,-0.00837,0.01076,-0.00900,0.01046,-0.00957,0.01006,-0.01006,0.00957,-0.01046,0.00900,-0.01076,0.00837,-0.01094,0.00770,-0.01100,0.00700,-0.01100,-0.00700,-0.01094,-0.00769,-0.01076,-0.00837,-0.01046,-0.00900,-0.01006,-0.00957,-0.00957,-0.01006,-0.00900,-0.01046,-0.00837,-0.01076,-0.00769,-0.01094,-0.00700,-0.01100,0.00700,-0.01100,0.00770,-0.01094,0.00837,-0.01076,0.00900,-0.01046,0.00957,-0.01006,0.01006,-0.00957,0.01046,-0.00900,0.01076,-0.00837,0.01094,-0.00769,0.01100,-0.00700,0.01100,0.00700,0.01094,0.00770,0.01076,0.00837,0.01046,0.00900,0.01006,0.00957,0.00957,0.01006,0.00900,0.01046,0.00837,0.01076,0.00770,0.01094,0.00700,0.01100,0.00000*
%
%AMMACRO31*
4,1,40,0.01700,-0.01300,0.01700,0.01300,0.01694,0.01370,0.01676,0.01437,0.01646,0.01500,0.01606,0.01557,0.01557,0.01606,0.01500,0.01646,0.01437,0.01676,0.01370,0.01694,0.01300,0.01700,-0.01300,0.01700,-0.01369,0.01694,-0.01437,0.01676,-0.01500,0.01646,-0.01557,0.01606,-0.01606,0.01557,-0.01646,0.01500,-0.01676,0.01437,-0.01694,0.01370,-0.01700,0.01300,-0.01700,-0.01300,-0.01694,-0.01369,-0.01676,-0.01437,-0.01646,-0.01500,-0.01606,-0.01557,-0.01557,-0.01606,-0.01500,-0.01646,-0.01437,-0.01676,-0.01369,-0.01694,-0.01300,-0.01700,0.01300,-0.01700,0.01370,-0.01694,0.01437,-0.01676,0.01500,-0.01646,0.01557,-0.01606,0.01606,-0.01557,0.01646,-0.01500,0.01676,-0.01437,0.01694,-0.01369,0.01700,-0.01300,0.00000*
%
%AMMACRO35*
4,1,40,-0.01300,-0.01700,0.01300,-0.01700,0.01370,-0.01694,0.01437,-0.01676,0.01500,-0.01646,0.01557,-0.01606,0.01606,-0.01557,0.01646,-0.01500,0.01676,-0.01437,0.01694,-0.01369,0.01700,-0.01300,0.01700,0.01300,0.01694,0.01370,0.01676,0.01437,0.01646,0.01500,0.01606,0.01557,0.01557,0.01606,0.01500,0.01646,0.01437,0.01676,0.01370,0.01694,0.01300,0.01700,-0.01300,0.01700,-0.01369,0.01694,-0.01437,0.01676,-0.01500,0.01646,-0.01557,0.01606,-0.01606,0.01557,-0.01646,0.01500,-0.01676,0.01437,-0.01694,0.01370,-0.01700,0.01300,-0.01700,-0.01300,-0.01694,-0.01369,-0.01676,-0.01437,-0.01646,-0.01500,-0.01606,-0.01557,-0.01557,-0.01606,-0.01500,-0.01646,-0.01437,-0.01676,-0.01369,-0.01694,-0.01300,-0.01700,0.00000*
%
%AMMACRO36*
4,1,40,-0.01300,-0.01700,0.01300,-0.01700,0.01370,-0.01694,0.01437,-0.01676,0.01500,-0.01646,0.01557,-0.01606,0.01606,-0.01557,0.01646,-0.01500,0.01676,-0.01437,0.01694,-0.01369,0.01700,-0.01300,0.01700,0.01300,0.01694,0.01370,0.01676,0.01437,0.01646,0.01500,0.01606,0.01557,0.01557,0.01606,0.01500,0.01646,0.01437,0.01676,0.01370,0.01694,0.01300,0.01700,-0.01300,0.01700,-0.01369,0.01694,-0.01437,0.01676,-0.01500,0.01646,-0.01557,0.01606,-0.01606,0.01557,-0.01646,0.01500,-0.01676,0.01437,-0.01694,0.01370,-0.01700,0.01300,-0.01700,-0.01300,-0.01694,-0.01369,-0.01676,-0.01437,-0.01646,-0.01500,-0.01606,-0.01557,-0.01557,-0.01606,-0.01500,-0.01646,-0.01437,-0.01676,-0.01369,-0.01694,-0.01300,-0.01700,0.00000*
%
%AMMACRO40*
4,1,40,0.01300,0.01700,-0.01300,0.01700,-0.01369,0.01694,-0.01437,0.01676,-0.01500,0.01646,-0.01557,0.01606,-0.01606,0.01557,-0.01646,0.01500,-0.01676,0.01437,-0.01694,0.01370,-0.01700,0.01300,-0.01700,-0.01300,-0.01694,-0.01369,-0.01676,-0.01437,-0.01646,-0.01500,-0.01606,-0.01557,-0.01557,-0.01606,-0.01500,-0.01646,-0.01437,-0.01676,-0.01369,-0.01694,-0.01300,-0.01700,0.01300,-0.01700,0.01370,-0.01694,0.01437,-0.01676,0.01500,-0.01646,0.01557,-0.01606,0.01606,-0.01557,0.01646,-0.01500,0.01676,-0.01437,0.01694,-0.01369,0.01700,-0.01300,0.01700,0.01300,0.01694,0.01370,0.01676,0.01437,0.01646,0.01500,0.01606,0.01557,0.01557,0.01606,0.01500,0.01646,0.01437,0.01676,0.01370,0.01694,0.01300,0.01700,0.00000*
%
%AMMACRO41*
4,1,40,0.01100,-0.00700,0.01100,0.00700,0.01094,0.00770,0.01076,0.00837,0.01046,0.00900,0.01006,0.00957,0.00957,0.01006,0.00900,0.01046,0.00837,0.01076,0.00770,0.01094,0.00700,0.01100,-0.00700,0.01100,-0.00769,0.01094,-0.00837,0.01076,-0.00900,0.01046,-0.00957,0.01006,-0.01006,0.00957,-0.01046,0.00900,-0.01076,0.00837,-0.01094,0.00770,-0.01100,0.00700,-0.01100,-0.00700,-0.01094,-0.00769,-0.01076,-0.00837,-0.01046,-0.00900,-0.01006,-0.00957,-0.00957,-0.01006,-0.00900,-0.01046,-0.00837,-0.01076,-0.00769,-0.01094,-0.00700,-0.01100,0.00700,-0.01100,0.00770,-0.01094,0.00837,-0.01076,0.00900,-0.01046,0.00957,-0.01006,0.01006,-0.00957,0.01046,-0.00900,0.01076,-0.00837,0.01094,-0.00769,0.01100,-0.00700,0.00000*
%
%AMMACRO42*
4,1,40,0.01100,-0.00700,0.01100,0.00700,0.01094,0.00770,0.01076,0.00837,0.01046,0.00900,0.01006,0.00957,0.00957,0.01006,0.00900,0.01046,0.00837,0.01076,0.00770,0.01094,0.00700,0.01100,-0.00700,0.01100,-0.00769,0.01094,-0.00837,0.01076,-0.00900,0.01046,-0.00957,0.01006,-0.01006,0.00957,-0.01046,0.00900,-0.01076,0.00837,-0.01094,0.00770,-0.01100,0.00700,-0.01100,-0.00700,-0.01094,-0.00769,-0.01076,-0.00837,-0.01046,-0.00900,-0.01006,-0.00957,-0.00957,-0.01006,-0.00900,-0.01046,-0.00837,-0.01076,-0.00769,-0.01094,-0.00700,-0.01100,0.00700,-0.01100,0.00770,-0.01094,0.00837,-0.01076,0.00900,-0.01046,0.00957,-0.01006,0.01006,-0.00957,0.01046,-0.00900,0.01076,-0.00837,0.01094,-0.00769,0.01100,-0.00700,0.00000*
%
%AMMACRO43*
4,1,40,0.00800,0.01200,-0.00800,0.01200,-0.00869,0.01194,-0.00937,0.01176,-0.01000,0.01146,-0.01057,0.01106,-0.01106,0.01057,-0.01146,0.01000,-0.01176,0.00937,-0.01194,0.00870,-0.01200,0.00800,-0.01200,-0.00800,-0.01194,-0.00869,-0.01176,-0.00937,-0.01146,-0.01000,-0.01106,-0.01057,-0.01057,-0.01106,-0.01000,-0.01146,-0.00937,-0.01176,-0.00869,-0.01194,-0.00800,-0.01200,0.00800,-0.01200,0.00870,-0.01194,0.00937,-0.01176,0.01000,-0.01146,0.01057,-0.01106,0.01106,-0.01057,0.01146,-0.01000,0.01176,-0.00937,0.01194,-0.00869,0.01200,-0.00800,0.01200,0.00800,0.01194,0.00870,0.01176,0.00937,0.01146,0.01000,0.01106,0.01057,0.01057,0.01106,0.01000,0.01146,0.00937,0.01176,0.00870,0.01194,0.00800,0.01200,0.00000*
%
%AMMACRO44*
4,1,40,0.00800,0.01200,-0.00800,0.01200,-0.00869,0.01194,-0.00937,0.01176,-0.01000,0.01146,-0.01057,0.01106,-0.01106,0.01057,-0.01146,0.01000,-0.01176,0.00937,-0.01194,0.00870,-0.01200,0.00800,-0.01200,-0.00800,-0.01194,-0.00869,-0.01176,-0.00937,-0.01146,-0.01000,-0.01106,-0.01057,-0.01057,-0.01106,-0.01000,-0.01146,-0.00937,-0.01176,-0.00869,-0.01194,-0.00800,-0.01200,0.00800,-0.01200,0.00870,-0.01194,0.00937,-0.01176,0.01000,-0.01146,0.01057,-0.01106,0.01106,-0.01057,0.01146,-0.01000,0.01176,-0.00937,0.01194,-0.00869,0.01200,-0.00800,0.01200,0.00800,0.01194,0.00870,0.01176,0.00937,0.01146,0.01000,0.01106,0.01057,0.01057,0.01106,0.01000,0.01146,0.00937,0.01176,0.00870,0.01194,0.00800,0.01200,0.00000*
%
%AMMACRO49*
4,1,40,-0.01700,0.01300,-0.01700,-0.01300,-0.01694,-0.01369,-0.01676,-0.01437,-0.01646,-0.01500,-0.01606,-0.01557,-0.01557,-0.01606,-0.01500,-0.01646,-0.01437,-0.01676,-0.01369,-0.01694,-0.01300,-0.01700,0.01300,-0.01700,0.01370,-0.01694,0.01437,-0.01676,0.01500,-0.01646,0.01557,-0.01606,0.01606,-0.01557,0.01646,-0.01500,0.01676,-0.01437,0.01694,-0.01369,0.01700,-0.01300,0.01700,0.01300,0.01694,0.01370,0.01676,0.01437,0.01646,0.01500,0.01606,0.01557,0.01557,0.01606,0.01500,0.01646,0.01437,0.01676,0.01370,0.01694,0.01300,0.01700,-0.01300,0.01700,-0.01369,0.01694,-0.01437,0.01676,-0.01500,0.01646,-0.01557,0.01606,-0.01606,0.01557,-0.01646,0.01500,-0.01676,0.01437,-0.01694,0.01370,-0.01700,0.01300,0.00000*
%
%AMMACRO50*
4,1,40,-0.01700,0.01300,-0.01700,-0.01300,-0.01694,-0.01369,-0.01676,-0.01437,-0.01646,-0.01500,-0.01606,-0.01557,-0.01557,-0.01606,-0.01500,-0.01646,-0.01437,-0.01676,-0.01369,-0.01694,-0.01300,-0.01700,0.01300,-0.01700,0.01370,-0.01694,0.01437,-0.01676,0.01500,-0.01646,0.01557,-0.01606,0.01606,-0.01557,0.01646,-0.01500,0.01676,-0.01437,0.01694,-0.01369,0.01700,-0.01300,0.01700,0.01300,0.01694,0.01370,0.01676,0.01437,0.01646,0.01500,0.01606,0.01557,0.01557,0.01606,0.01500,0.01646,0.01437,0.01676,0.01370,0.01694,0.01300,0.01700,-0.01300,0.01700,-0.01369,0.01694,-0.01437,0.01676,-0.01500,0.01646,-0.01557,0.01606,-0.01606,0.01557,-0.01646,0.01500,-0.01676,0.01437,-0.01694,0.01370,-0.01700,0.01300,0.00000*
%
%AMMACRO66*
4,1,40,-0.01200,0.00800,-0.01200,-0.00800,-0.01194,-0.00869,-0.01176,-0.00937,-0.01146,-0.01000,-0.01106,-0.01057,-0.01057,-0.01106,-0.01000,-0.01146,-0.00937,-0.01176,-0.00869,-0.01194,-0.00800,-0.01200,0.00800,-0.01200,0.00870,-0.01194,0.00937,-0.01176,0.01000,-0.01146,0.01057,-0.01106,0.01106,-0.01057,0.01146,-0.01000,0.01176,-0.00937,0.01194,-0.00869,0.01200,-0.00800,0.01200,0.00800,0.01194,0.00870,0.01176,0.00937,0.01146,0.01000,0.01106,0.01057,0.01057,0.01106,0.01000,0.01146,0.00937,0.01176,0.00870,0.01194,0.00800,0.01200,-0.00800,0.01200,-0.00869,0.01194,-0.00937,0.01176,-0.01000,0.01146,-0.01057,0.01106,-0.01106,0.01057,-0.01146,0.01000,-0.01176,0.00937,-0.01194,0.00870,-0.01200,0.00800,0.00000*
%
%AMMACRO67*
4,1,40,-0.01200,0.00800,-0.01200,-0.00800,-0.01194,-0.00869,-0.01176,-0.00937,-0.01146,-0.01000,-0.01106,-0.01057,-0.01057,-0.01106,-0.01000,-0.01146,-0.00937,-0.01176,-0.00869,-0.01194,-0.00800,-0.01200,0.00800,-0.01200,0.00870,-0.01194,0.00937,-0.01176,0.01000,-0.01146,0.01057,-0.01106,0.01106,-0.01057,0.01146,-0.01000,0.01176,-0.00937,0.01194,-0.00869,0.01200,-0.00800,0.01200,0.00800,0.01194,0.00870,0.01176,0.00937,0.01146,0.01000,0.01106,0.01057,0.01057,0.01106,0.01000,0.01146,0.00937,0.01176,0.00870,0.01194,0.00800,0.01200,-0.00800,0.01200,-0.00869,0.01194,-0.00937,0.01176,-0.01000,0.01146,-0.01057,0.01106,-0.01106,0.01057,-0.01146,0.01000,-0.01176,0.00937,-0.01194,0.00870,-0.01200,0.00800,0.00000*
%
%AMMACRO75*
4,1,40,-0.00700,-0.02250,-0.00839,-0.02238,-0.00974,-0.02202,-0.01100,-0.02143,-0.01214,-0.02063,-0.01313,-0.01964,-0.01393,-0.01850,-0.01452,-0.01724,-0.01488,-0.01589,-0.01500,-0.01450,-0.01500,0.01450,-0.01488,0.01589,-0.01452,0.01724,-0.01393,0.01850,-0.01313,0.01964,-0.01214,0.02063,-0.01100,0.02143,-0.00974,0.02202,-0.00839,0.02238,-0.00700,0.02250,0.00700,0.02250,0.00839,0.02238,0.00974,0.02202,0.01100,0.02143,0.01214,0.02063,0.01313,0.01964,0.01393,0.01850,0.01452,0.01724,0.01488,0.01589,0.01500,0.01450,0.01500,-0.01450,0.01488,-0.01589,0.01452,-0.01724,0.01393,-0.01850,0.01313,-0.01964,0.01214,-0.02063,0.01100,-0.02143,0.00974,-0.02202,0.00839,-0.02238,0.00700,-0.02250,-0.00700,-0.02250,0.00000*
%
%AMMACRO79*
4,1,25,-0.26969,-0.01299,-0.26969,-0.83465,0.26969,-0.83465,0.26969,0.83465,-0.26969,0.83465,-0.26969,0.12087,-0.22638,0.12087,-0.21476,0.11985,-0.20349,0.11683,-0.19291,0.11190,-0.18336,0.10521,-0.17511,0.09696,-0.16842,0.08741,-0.16349,0.07683,-0.16047,0.06556,-0.15945,0.05394,-0.16047,0.04232,-0.16349,0.03105,-0.16842,0.02048,-0.17511,0.01092,-0.18336,0.00267,-0.19291,-0.00402,-0.20349,-0.00895,-0.21476,-0.01197,-0.22638,-0.01299,-0.26969,-0.01299,0.00000*
%
%AMMACRO82*
4,1,40,-0.01400,-0.00800,-0.01400,0.00800,-0.01394,0.00870,-0.01376,0.00937,-0.01346,0.01000,-0.01306,0.01057,-0.01257,0.01106,-0.01200,0.01146,-0.01137,0.01176,-0.01069,0.01194,-0.01000,0.01200,0.01000,0.01200,0.01070,0.01194,0.01137,0.01176,0.01200,0.01146,0.01257,0.01106,0.01306,0.01057,0.01346,0.01000,0.01376,0.00937,0.01394,0.00870,0.01400,0.00800,0.01400,-0.00800,0.01394,-0.00869,0.01376,-0.00937,0.01346,-0.01000,0.01306,-0.01057,0.01257,-0.01106,0.01200,-0.01146,0.01137,-0.01176,0.01070,-0.01194,0.01000,-0.01200,-0.01000,-0.01200,-0.01069,-0.01194,-0.01137,-0.01176,-0.01200,-0.01146,-0.01257,-0.01106,-0.01306,-0.01057,-0.01346,-0.01000,-0.01376,-0.00937,-0.01394,-0.00869,-0.01400,-0.00800,0.00000*
%
%AMMACRO84*
4,1,40,0.00700,0.02250,0.00839,0.02238,0.00974,0.02202,0.01100,0.02143,0.01214,0.02063,0.01313,0.01964,0.01393,0.01850,0.01452,0.01724,0.01488,0.01589,0.01500,0.01450,0.01500,-0.01450,0.01488,-0.01589,0.01452,-0.01724,0.01393,-0.01850,0.01313,-0.01964,0.01214,-0.02063,0.01100,-0.02143,0.00974,-0.02202,0.00839,-0.02238,0.00700,-0.02250,-0.00700,-0.02250,-0.00839,-0.02238,-0.00974,-0.02202,-0.01100,-0.02143,-0.01214,-0.02063,-0.01313,-0.01964,-0.01393,-0.01850,-0.01452,-0.01724,-0.01488,-0.01589,-0.01500,-0.01450,-0.01500,0.01450,-0.01488,0.01589,-0.01452,0.01724,-0.01393,0.01850,-0.01313,0.01964,-0.01214,0.02063,-0.01100,0.02143,-0.00974,0.02202,-0.00839,0.02238,-0.00700,0.02250,0.00700,0.02250,0.00000*
%
%AMMACRO38*
4,1,40,0.01200,-0.00800,0.01200,0.00800,0.01194,0.00870,0.01176,0.00937,0.01146,0.01000,0.01106,0.01057,0.01057,0.01106,0.01000,0.01146,0.00937,0.01176,0.00870,0.01194,0.00800,0.01200,-0.00800,0.01200,-0.00869,0.01194,-0.00937,0.01176,-0.01000,0.01146,-0.01057,0.01106,-0.01106,0.01057,-0.01146,0.01000,-0.01176,0.00937,-0.01194,0.00870,-0.01200,0.00800,-0.01200,-0.00800,-0.01194,-0.00869,-0.01176,-0.00937,-0.01146,-0.01000,-0.01106,-0.01057,-0.01057,-0.01106,-0.01000,-0.01146,-0.00937,-0.01176,-0.00869,-0.01194,-0.00800,-0.01200,0.00800,-0.01200,0.00870,-0.01194,0.00937,-0.01176,0.01000,-0.01146,0.01057,-0.01106,0.01106,-0.01057,0.01146,-0.01000,0.01176,-0.00937,0.01194,-0.00869,0.01200,-0.00800,0.00000*
%
%AMMACRO28*
4,1,40,-0.00800,-0.01200,0.00800,-0.01200,0.00870,-0.01194,0.00937,-0.01176,0.01000,-0.01146,0.01057,-0.01106,0.01106,-0.01057,0.01146,-0.01000,0.01176,-0.00937,0.01194,-0.00869,0.01200,-0.00800,0.01200,0.00800,0.01194,0.00870,0.01176,0.00937,0.01146,0.01000,0.01106,0.01057,0.01057,0.01106,0.01000,0.01146,0.00937,0.01176,0.00870,0.01194,0.00800,0.01200,-0.00800,0.01200,-0.00869,0.01194,-0.00937,0.01176,-0.01000,0.01146,-0.01057,0.01106,-0.01106,0.01057,-0.01146,0.01000,-0.01176,0.00937,-0.01194,0.00870,-0.01200,0.00800,-0.01200,-0.00800,-0.01194,-0.00869,-0.01176,-0.00937,-0.01146,-0.01000,-0.01106,-0.01057,-0.01057,-0.01106,-0.01000,-0.01146,-0.00937,-0.01176,-0.00869,-0.01194,-0.00800,-0.01200,0.00000*
%
%AMMACRO24*
4,1,40,-0.00700,-0.01100,0.00700,-0.01100,0.00770,-0.01094,0.00837,-0.01076,0.00900,-0.01046,0.00957,-0.01006,0.01006,-0.00957,0.01046,-0.00900,0.01076,-0.00837,0.01094,-0.00769,0.01100,-0.00700,0.01100,0.00700,0.01094,0.00770,0.01076,0.00837,0.01046,0.00900,0.01006,0.00957,0.00957,0.01006,0.00900,0.01046,0.00837,0.01076,0.00770,0.01094,0.00700,0.01100,-0.00700,0.01100,-0.00769,0.01094,-0.00837,0.01076,-0.00900,0.01046,-0.00957,0.01006,-0.01006,0.00957,-0.01046,0.00900,-0.01076,0.00837,-0.01094,0.00770,-0.01100,0.00700,-0.01100,-0.00700,-0.01094,-0.00769,-0.01076,-0.00837,-0.01046,-0.00900,-0.01006,-0.00957,-0.00957,-0.01006,-0.00900,-0.01046,-0.00837,-0.01076,-0.00769,-0.01094,-0.00700,-0.01100,0.00000*
%
%AMMACRO19*
4,1,40,-0.01100,0.00700,-0.01100,-0.00700,-0.01094,-0.00769,-0.01076,-0.00837,-0.01046,-0.00900,-0.01006,-0.00957,-0.00957,-0.01006,-0.00900,-0.01046,-0.00837,-0.01076,-0.00769,-0.01094,-0.00700,-0.01100,0.00700,-0.01100,0.00770,-0.01094,0.00837,-0.01076,0.00900,-0.01046,0.00957,-0.01006,0.01006,-0.00957,0.01046,-0.00900,0.01076,-0.00837,0.01094,-0.00769,0.01100,-0.00700,0.01100,0.00700,0.01094,0.00770,0.01076,0.00837,0.01046,0.00900,0.01006,0.00957,0.00957,0.01006,0.00900,0.01046,0.00837,0.01076,0.00770,0.01094,0.00700,0.01100,-0.00700,0.01100,-0.00769,0.01094,-0.00837,0.01076,-0.00900,0.01046,-0.00957,0.01006,-0.01006,0.00957,-0.01046,0.00900,-0.01076,0.00837,-0.01094,0.00770,-0.01100,0.00700,0.00000*
%
%AMMACRO30*
4,1,40,0.01700,-0.01300,0.01700,0.01300,0.01694,0.01370,0.01676,0.01437,0.01646,0.01500,0.01606,0.01557,0.01557,0.01606,0.01500,0.01646,0.01437,0.01676,0.01370,0.01694,0.01300,0.01700,-0.01300,0.01700,-0.01369,0.01694,-0.01437,0.01676,-0.01500,0.01646,-0.01557,0.01606,-0.01606,0.01557,-0.01646,0.01500,-0.01676,0.01437,-0.01694,0.01370,-0.01700,0.01300,-0.01700,-0.01300,-0.01694,-0.01369,-0.01676,-0.01437,-0.01646,-0.01500,-0.01606,-0.01557,-0.01557,-0.01606,-0.01500,-0.01646,-0.01437,-0.01676,-0.01369,-0.01694,-0.01300,-0.01700,0.01300,-0.01700,0.01370,-0.01694,0.01437,-0.01676,0.01500,-0.01646,0.01557,-0.01606,0.01606,-0.01557,0.01646,-0.01500,0.01676,-0.01437,0.01694,-0.01369,0.01700,-0.01300,0.00000*
%
%AMMACRO17*
4,1,40,0.01300,0.01700,-0.01300,0.01700,-0.01369,0.01694,-0.01437,0.01676,-0.01500,0.01646,-0.01557,0.01606,-0.01606,0.01557,-0.01646,0.01500,-0.01676,0.01437,-0.01694,0.01370,-0.01700,0.01300,-0.01700,-0.01300,-0.01694,-0.01369,-0.01676,-0.01437,-0.01646,-0.01500,-0.01606,-0.01557,-0.01557,-0.01606,-0.01500,-0.01646,-0.01437,-0.01676,-0.01369,-0.01694,-0.01300,-0.01700,0.01300,-0.01700,0.01370,-0.01694,0.01437,-0.01676,0.01500,-0.01646,0.01557,-0.01606,0.01606,-0.01557,0.01646,-0.01500,0.01676,-0.01437,0.01694,-0.01369,0.01700,-0.01300,0.01700,0.01300,0.01694,0.01370,0.01676,0.01437,0.01646,0.01500,0.01606,0.01557,0.01557,0.01606,0.01500,0.01646,0.01437,0.01676,0.01370,0.01694,0.01300,0.01700,0.00000*
%
%AMMACRO65*
4,1,25,0.26969,-0.01299,0.26969,-0.83465,-0.26969,-0.83465,-0.26969,0.83465,0.26969,0.83465,0.26969,0.12087,0.22638,0.12087,0.21476,0.11985,0.20349,0.11683,0.19292,0.11190,0.18336,0.10521,0.17511,0.09696,0.16842,0.08741,0.16349,0.07683,0.16047,0.06556,0.15945,0.05394,0.16047,0.04232,0.16349,0.03105,0.16842,0.02048,0.17511,0.01092,0.18336,0.00267,0.19292,-0.00402,0.20349,-0.00895,0.21476,-0.01197,0.22638,-0.01299,0.26969,-0.01299,0.00000*
%
%AMMACRO37*
4,1,40,0.01200,-0.00800,0.01200,0.00800,0.01194,0.00870,0.01176,0.00937,0.01146,0.01000,0.01106,0.01057,0.01057,0.01106,0.01000,0.01146,0.00937,0.01176,0.00870,0.01194,0.00800,0.01200,-0.00800,0.01200,-0.00869,0.01194,-0.00937,0.01176,-0.01000,0.01146,-0.01057,0.01106,-0.01106,0.01057,-0.01146,0.01000,-0.01176,0.00937,-0.01194,0.00870,-0.01200,0.00800,-0.01200,-0.00800,-0.01194,-0.00869,-0.01176,-0.00937,-0.01146,-0.01000,-0.01106,-0.01057,-0.01057,-0.01106,-0.01000,-0.01146,-0.00937,-0.01176,-0.00869,-0.01194,-0.00800,-0.01200,0.00800,-0.01200,0.00870,-0.01194,0.00937,-0.01176,0.01000,-0.01146,0.01057,-0.01106,0.01106,-0.01057,0.01146,-0.01000,0.01176,-0.00937,0.01194,-0.00869,0.01200,-0.00800,0.00000*
%
%AMMACRO27*
4,1,40,-0.00800,-0.01200,0.00800,-0.01200,0.00870,-0.01194,0.00937,-0.01176,0.01000,-0.01146,0.01057,-0.01106,0.01106,-0.01057,0.01146,-0.01000,0.01176,-0.00937,0.01194,-0.00869,0.01200,-0.00800,0.01200,0.00800,0.01194,0.00870,0.01176,0.00937,0.01146,0.01000,0.01106,0.01057,0.01057,0.01106,0.01000,0.01146,0.00937,0.01176,0.00870,0.01194,0.00800,0.01200,-0.00800,0.01200,-0.00869,0.01194,-0.00937,0.01176,-0.01000,0.01146,-0.01057,0.01106,-0.01106,0.01057,-0.01146,0.01000,-0.01176,0.00937,-0.01194,0.00870,-0.01200,0.00800,-0.01200,-0.00800,-0.01194,-0.00869,-0.01176,-0.00937,-0.01146,-0.01000,-0.01106,-0.01057,-0.01057,-0.01106,-0.01000,-0.01146,-0.00937,-0.01176,-0.00869,-0.01194,-0.00800,-0.01200,0.00000*
%
%AMMACRO21*
4,1,40,-0.00700,-0.01100,0.00700,-0.01100,0.00770,-0.01094,0.00837,-0.01076,0.00900,-0.01046,0.00957,-0.01006,0.01006,-0.00957,0.01046,-0.00900,0.01076,-0.00837,0.01094,-0.00769,0.01100,-0.00700,0.01100,0.00700,0.01094,0.00770,0.01076,0.00837,0.01046,0.00900,0.01006,0.00957,0.00957,0.01006,0.00900,0.01046,0.00837,0.01076,0.00770,0.01094,0.00700,0.01100,-0.00700,0.01100,-0.00769,0.01094,-0.00837,0.01076,-0.00900,0.01046,-0.00957,0.01006,-0.01006,0.00957,-0.01046,0.00900,-0.01076,0.00837,-0.01094,0.00770,-0.01100,0.00700,-0.01100,-0.00700,-0.01094,-0.00769,-0.01076,-0.00837,-0.01046,-0.00900,-0.01006,-0.00957,-0.00957,-0.01006,-0.00900,-0.01046,-0.00837,-0.01076,-0.00769,-0.01094,-0.00700,-0.01100,0.00000*
%
%AMMACRO20*
4,1,40,-0.01100,0.00700,-0.01100,-0.00700,-0.01094,-0.00769,-0.01076,-0.00837,-0.01046,-0.00900,-0.01006,-0.00957,-0.00957,-0.01006,-0.00900,-0.01046,-0.00837,-0.01076,-0.00769,-0.01094,-0.00700,-0.01100,0.00700,-0.01100,0.00770,-0.01094,0.00837,-0.01076,0.00900,-0.01046,0.00957,-0.01006,0.01006,-0.00957,0.01046,-0.00900,0.01076,-0.00837,0.01094,-0.00769,0.01100,-0.00700,0.01100,0.00700,0.01094,0.00770,0.01076,0.00837,0.01046,0.00900,0.01006,0.00957,0.00957,0.01006,0.00900,0.01046,0.00837,0.01076,0.00770,0.01094,0.00700,0.01100,-0.00700,0.01100,-0.00769,0.01094,-0.00837,0.01076,-0.00900,0.01046,-0.00957,0.01006,-0.01006,0.00957,-0.01046,0.00900,-0.01076,0.00837,-0.01094,0.00770,-0.01100,0.00700,0.00000*
%
%AMMACRO20_180*
4,1,40,0.01100,-0.00700,0.01100,0.00700,0.01094,0.00769,0.01076,0.00837,0.01046,0.00900,0.01006,0.00957,0.00957,0.01006,0.00900,0.01046,0.00837,0.01076,0.00769,0.01094,0.00700,0.01100,-0.00700,0.01100,-0.00770,0.01094,-0.00837,0.01076,-0.00900,0.01046,-0.00957,0.01006,-0.01006,0.00957,-0.01046,0.00900,-0.01076,0.00837,-0.01094,0.00769,-0.01100,0.00700,-0.01100,-0.00700,-0.01094,-0.00770,-0.01076,-0.00837,-0.01046,-0.00900,-0.01006,-0.00957,-0.00957,-0.01006,-0.00900,-0.01046,-0.00837,-0.01076,-0.00770,-0.01094,-0.00700,-0.01100,0.00700,-0.01100,0.00769,-0.01094,0.00837,-0.01076,0.00900,-0.01046,0.00957,-0.01006,0.01006,-0.00957,0.01046,-0.00900,0.01076,-0.00837,0.01094,-0.00770,0.01100,-0.00700,0.00000*
%
%AMMACRO21_180*
4,1,40,0.00700,0.01100,-0.00700,0.01100,-0.00770,0.01094,-0.00837,0.01076,-0.00900,0.01046,-0.00957,0.01006,-0.01006,0.00957,-0.01046,0.00900,-0.01076,0.00837,-0.01094,0.00769,-0.01100,0.00700,-0.01100,-0.00700,-0.01094,-0.00770,-0.01076,-0.00837,-0.01046,-0.00900,-0.01006,-0.00957,-0.00957,-0.01006,-0.00900,-0.01046,-0.00837,-0.01076,-0.00770,-0.01094,-0.00700,-0.01100,0.00700,-0.01100,0.00769,-0.01094,0.00837,-0.01076,0.00900,-0.01046,0.00957,-0.01006,0.01006,-0.00957,0.01046,-0.00900,0.01076,-0.00837,0.01094,-0.00770,0.01100,-0.00700,0.01100,0.00700,0.01094,0.00769,0.01076,0.00837,0.01046,0.00900,0.01006,0.00957,0.00957,0.01006,0.00900,0.01046,0.00837,0.01076,0.00769,0.01094,0.00700,0.01100,0.00000*
%
%AMMACRO30_180*
4,1,40,-0.01700,0.01300,-0.01700,-0.01300,-0.01694,-0.01370,-0.01676,-0.01437,-0.01646,-0.01500,-0.01606,-0.01557,-0.01557,-0.01606,-0.01500,-0.01646,-0.01437,-0.01676,-0.01370,-0.01694,-0.01300,-0.01700,0.01300,-0.01700,0.01369,-0.01694,0.01437,-0.01676,0.01500,-0.01646,0.01557,-0.01606,0.01606,-0.01557,0.01646,-0.01500,0.01676,-0.01437,0.01694,-0.01370,0.01700,-0.01300,0.01700,0.01300,0.01694,0.01369,0.01676,0.01437,0.01646,0.01500,0.01606,0.01557,0.01557,0.01606,0.01500,0.01646,0.01437,0.01676,0.01369,0.01694,0.01300,0.01700,-0.01300,0.01700,-0.01370,0.01694,-0.01437,0.01676,-0.01500,0.01646,-0.01557,0.01606,-0.01606,0.01557,-0.01646,0.01500,-0.01676,0.01437,-0.01694,0.01369,-0.01700,0.01300,0.00000*
%
%AMMACRO31_180*
4,1,40,-0.01700,0.01300,-0.01700,-0.01300,-0.01694,-0.01370,-0.01676,-0.01437,-0.01646,-0.01500,-0.01606,-0.01557,-0.01557,-0.01606,-0.01500,-0.01646,-0.01437,-0.01676,-0.01370,-0.01694,-0.01300,-0.01700,0.01300,-0.01700,0.01369,-0.01694,0.01437,-0.01676,0.01500,-0.01646,0.01557,-0.01606,0.01606,-0.01557,0.01646,-0.01500,0.01676,-0.01437,0.01694,-0.01370,0.01700,-0.01300,0.01700,0.01300,0.01694,0.01369,0.01676,0.01437,0.01646,0.01500,0.01606,0.01557,0.01557,0.01606,0.01500,0.01646,0.01437,0.01676,0.01369,0.01694,0.01300,0.01700,-0.01300,0.01700,-0.01370,0.01694,-0.01437,0.01676,-0.01500,0.01646,-0.01557,0.01606,-0.01606,0.01557,-0.01646,0.01500,-0.01676,0.01437,-0.01694,0.01369,-0.01700,0.01300,0.00000*
%
%AMMACRO40_180*
4,1,40,-0.01300,-0.01700,0.01300,-0.01700,0.01369,-0.01694,0.01437,-0.01676,0.01500,-0.01646,0.01557,-0.01606,0.01606,-0.01557,0.01646,-0.01500,0.01676,-0.01437,0.01694,-0.01370,0.01700,-0.01300,0.01700,0.01300,0.01694,0.01369,0.01676,0.01437,0.01646,0.01500,0.01606,0.01557,0.01557,0.01606,0.01500,0.01646,0.01437,0.01676,0.01369,0.01694,0.01300,0.01700,-0.01300,0.01700,-0.01370,0.01694,-0.01437,0.01676,-0.01500,0.01646,-0.01557,0.01606,-0.01606,0.01557,-0.01646,0.01500,-0.01676,0.01437,-0.01694,0.01369,-0.01700,0.01300,-0.01700,-0.01300,-0.01694,-0.01370,-0.01676,-0.01437,-0.01646,-0.01500,-0.01606,-0.01557,-0.01557,-0.01606,-0.01500,-0.01646,-0.01437,-0.01676,-0.01370,-0.01694,-0.01300,-0.01700,0.00000*
%
%AMMACRO50_180*
4,1,40,0.01700,-0.01300,0.01700,0.01300,0.01694,0.01369,0.01676,0.01437,0.01646,0.01500,0.01606,0.01557,0.01557,0.01606,0.01500,0.01646,0.01437,0.01676,0.01369,0.01694,0.01300,0.01700,-0.01300,0.01700,-0.01370,0.01694,-0.01437,0.01676,-0.01500,0.01646,-0.01557,0.01606,-0.01606,0.01557,-0.01646,0.01500,-0.01676,0.01437,-0.01694,0.01369,-0.01700,0.01300,-0.01700,-0.01300,-0.01694,-0.01370,-0.01676,-0.01437,-0.01646,-0.01500,-0.01606,-0.01557,-0.01557,-0.01606,-0.01500,-0.01646,-0.01437,-0.01676,-0.01370,-0.01694,-0.01300,-0.01700,0.01300,-0.01700,0.01369,-0.01694,0.01437,-0.01676,0.01500,-0.01646,0.01557,-0.01606,0.01606,-0.01557,0.01646,-0.01500,0.01676,-0.01437,0.01694,-0.01370,0.01700,-0.01300,0.00000*
%
%AMMACRO41_180*
4,1,40,-0.01100,0.00700,-0.01100,-0.00700,-0.01094,-0.00770,-0.01076,-0.00837,-0.01046,-0.00900,-0.01006,-0.00957,-0.00957,-0.01006,-0.00900,-0.01046,-0.00837,-0.01076,-0.00770,-0.01094,-0.00700,-0.01100,0.00700,-0.01100,0.00769,-0.01094,0.00837,-0.01076,0.00900,-0.01046,0.00957,-0.01006,0.01006,-0.00957,0.01046,-0.00900,0.01076,-0.00837,0.01094,-0.00770,0.01100,-0.00700,0.01100,0.00700,0.01094,0.00769,0.01076,0.00837,0.01046,0.00900,0.01006,0.00957,0.00957,0.01006,0.00900,0.01046,0.00837,0.01076,0.00769,0.01094,0.00700,0.01100,-0.00700,0.01100,-0.00770,0.01094,-0.00837,0.01076,-0.00900,0.01046,-0.00957,0.01006,-0.01006,0.00957,-0.01046,0.00900,-0.01076,0.00837,-0.01094,0.00769,-0.01100,0.00700,0.00000*
%
%AMMACRO24_180*
4,1,40,0.00700,0.01100,-0.00700,0.01100,-0.00770,0.01094,-0.00837,0.01076,-0.00900,0.01046,-0.00957,0.01006,-0.01006,0.00957,-0.01046,0.00900,-0.01076,0.00837,-0.01094,0.00769,-0.01100,0.00700,-0.01100,-0.00700,-0.01094,-0.00770,-0.01076,-0.00837,-0.01046,-0.00900,-0.01006,-0.00957,-0.00957,-0.01006,-0.00900,-0.01046,-0.00837,-0.01076,-0.00770,-0.01094,-0.00700,-0.01100,0.00700,-0.01100,0.00769,-0.01094,0.00837,-0.01076,0.00900,-0.01046,0.00957,-0.01006,0.01006,-0.00957,0.01046,-0.00900,0.01076,-0.00837,0.01094,-0.00770,0.01100,-0.00700,0.01100,0.00700,0.01094,0.00769,0.01076,0.00837,0.01046,0.00900,0.01006,0.00957,0.00957,0.01006,0.00900,0.01046,0.00837,0.01076,0.00769,0.01094,0.00700,0.01100,0.00000*
%
%AMMACRO42_180*
4,1,40,-0.01100,0.00700,-0.01100,-0.00700,-0.01094,-0.00770,-0.01076,-0.00837,-0.01046,-0.00900,-0.01006,-0.00957,-0.00957,-0.01006,-0.00900,-0.01046,-0.00837,-0.01076,-0.00770,-0.01094,-0.00700,-0.01100,0.00700,-0.01100,0.00769,-0.01094,0.00837,-0.01076,0.00900,-0.01046,0.00957,-0.01006,0.01006,-0.00957,0.01046,-0.00900,0.01076,-0.00837,0.01094,-0.00770,0.01100,-0.00700,0.01100,0.00700,0.01094,0.00769,0.01076,0.00837,0.01046,0.00900,0.01006,0.00957,0.00957,0.01006,0.00900,0.01046,0.00837,0.01076,0.00769,0.01094,0.00700,0.01100,-0.00700,0.01100,-0.00770,0.01094,-0.00837,0.01076,-0.00900,0.01046,-0.00957,0.01006,-0.01006,0.00957,-0.01046,0.00900,-0.01076,0.00837,-0.01094,0.00769,-0.01100,0.00700,0.00000*
%
%AMMACRO43_180*
4,1,40,-0.00800,-0.01200,0.00800,-0.01200,0.00869,-0.01194,0.00937,-0.01176,0.01000,-0.01146,0.01057,-0.01106,0.01106,-0.01057,0.01146,-0.01000,0.01176,-0.00937,0.01194,-0.00870,0.01200,-0.00800,0.01200,0.00800,0.01194,0.00869,0.01176,0.00937,0.01146,0.01000,0.01106,0.01057,0.01057,0.01106,0.01000,0.01146,0.00937,0.01176,0.00869,0.01194,0.00800,0.01200,-0.00800,0.01200,-0.00870,0.01194,-0.00937,0.01176,-0.01000,0.01146,-0.01057,0.01106,-0.01106,0.01057,-0.01146,0.01000,-0.01176,0.00937,-0.01194,0.00869,-0.01200,0.00800,-0.01200,-0.00800,-0.01194,-0.00870,-0.01176,-0.00937,-0.01146,-0.01000,-0.01106,-0.01057,-0.01057,-0.01106,-0.01000,-0.01146,-0.00937,-0.01176,-0.00870,-0.01194,-0.00800,-0.01200,0.00000*
%
%AMMACRO17_180*
4,1,40,-0.01300,-0.01700,0.01300,-0.01700,0.01369,-0.01694,0.01437,-0.01676,0.01500,-0.01646,0.01557,-0.01606,0.01606,-0.01557,0.01646,-0.01500,0.01676,-0.01437,0.01694,-0.01370,0.01700,-0.01300,0.01700,0.01300,0.01694,0.01369,0.01676,0.01437,0.01646,0.01500,0.01606,0.01557,0.01557,0.01606,0.01500,0.01646,0.01437,0.01676,0.01369,0.01694,0.01300,0.01700,-0.01300,0.01700,-0.01370,0.01694,-0.01437,0.01676,-0.01500,0.01646,-0.01557,0.01606,-0.01606,0.01557,-0.01646,0.01500,-0.01676,0.01437,-0.01694,0.01369,-0.01700,0.01300,-0.01700,-0.01300,-0.01694,-0.01370,-0.01676,-0.01437,-0.01646,-0.01500,-0.01606,-0.01557,-0.01557,-0.01606,-0.01500,-0.01646,-0.01437,-0.01676,-0.01370,-0.01694,-0.01300,-0.01700,0.00000*
%
%AMMACRO26_180*
4,1,40,-0.00700,-0.01100,0.00700,-0.01100,0.00769,-0.01094,0.00837,-0.01076,0.00900,-0.01046,0.00957,-0.01006,0.01006,-0.00957,0.01046,-0.00900,0.01076,-0.00837,0.01094,-0.00770,0.01100,-0.00700,0.01100,0.00700,0.01094,0.00769,0.01076,0.00837,0.01046,0.00900,0.01006,0.00957,0.00957,0.01006,0.00900,0.01046,0.00837,0.01076,0.00769,0.01094,0.00700,0.01100,-0.00700,0.01100,-0.00770,0.01094,-0.00837,0.01076,-0.00900,0.01046,-0.00957,0.01006,-0.01006,0.00957,-0.01046,0.00900,-0.01076,0.00837,-0.01094,0.00769,-0.01100,0.00700,-0.01100,-0.00700,-0.01094,-0.00770,-0.01076,-0.00837,-0.01046,-0.00900,-0.01006,-0.00957,-0.00957,-0.01006,-0.00900,-0.01046,-0.00837,-0.01076,-0.00770,-0.01094,-0.00700,-0.01100,0.00000*
%
%AMMACRO35_180*
4,1,40,0.01300,0.01700,-0.01300,0.01700,-0.01370,0.01694,-0.01437,0.01676,-0.01500,0.01646,-0.01557,0.01606,-0.01606,0.01557,-0.01646,0.01500,-0.01676,0.01437,-0.01694,0.01369,-0.01700,0.01300,-0.01700,-0.01300,-0.01694,-0.01370,-0.01676,-0.01437,-0.01646,-0.01500,-0.01606,-0.01557,-0.01557,-0.01606,-0.01500,-0.01646,-0.01437,-0.01676,-0.01370,-0.01694,-0.01300,-0.01700,0.01300,-0.01700,0.01369,-0.01694,0.01437,-0.01676,0.01500,-0.01646,0.01557,-0.01606,0.01606,-0.01557,0.01646,-0.01500,0.01676,-0.01437,0.01694,-0.01370,0.01700,-0.01300,0.01700,0.01300,0.01694,0.01369,0.01676,0.01437,0.01646,0.01500,0.01606,0.01557,0.01557,0.01606,0.01500,0.01646,0.01437,0.01676,0.01369,0.01694,0.01300,0.01700,0.00000*
%
%AMMACRO44_180*
4,1,40,-0.00800,-0.01200,0.00800,-0.01200,0.00869,-0.01194,0.00937,-0.01176,0.01000,-0.01146,0.01057,-0.01106,0.01106,-0.01057,0.01146,-0.01000,0.01176,-0.00937,0.01194,-0.00870,0.01200,-0.00800,0.01200,0.00800,0.01194,0.00869,0.01176,0.00937,0.01146,0.01000,0.01106,0.01057,0.01057,0.01106,0.01000,0.01146,0.00937,0.01176,0.00869,0.01194,0.00800,0.01200,-0.00800,0.01200,-0.00870,0.01194,-0.00937,0.01176,-0.01000,0.01146,-0.01057,0.01106,-0.01106,0.01057,-0.01146,0.01000,-0.01176,0.00937,-0.01194,0.00869,-0.01200,0.00800,-0.01200,-0.00800,-0.01194,-0.00870,-0.01176,-0.00937,-0.01146,-0.01000,-0.01106,-0.01057,-0.01057,-0.01106,-0.01000,-0.01146,-0.00937,-0.01176,-0.00870,-0.01194,-0.00800,-0.01200,0.00000*
%
%AMMACRO27_180*
4,1,40,0.00800,0.01200,-0.00800,0.01200,-0.00870,0.01194,-0.00937,0.01176,-0.01000,0.01146,-0.01057,0.01106,-0.01106,0.01057,-0.01146,0.01000,-0.01176,0.00937,-0.01194,0.00869,-0.01200,0.00800,-0.01200,-0.00800,-0.01194,-0.00870,-0.01176,-0.00937,-0.01146,-0.01000,-0.01106,-0.01057,-0.01057,-0.01106,-0.01000,-0.01146,-0.00937,-0.01176,-0.00870,-0.01194,-0.00800,-0.01200,0.00800,-0.01200,0.00869,-0.01194,0.00937,-0.01176,0.01000,-0.01146,0.01057,-0.01106,0.01106,-0.01057,0.01146,-0.01000,0.01176,-0.00937,0.01194,-0.00870,0.01200,-0.00800,0.01200,0.00800,0.01194,0.00869,0.01176,0.00937,0.01146,0.01000,0.01106,0.01057,0.01057,0.01106,0.01000,0.01146,0.00937,0.01176,0.00869,0.01194,0.00800,0.01200,0.00000*
%
%AMMACRO36_180*
4,1,40,0.01300,0.01700,-0.01300,0.01700,-0.01370,0.01694,-0.01437,0.01676,-0.01500,0.01646,-0.01557,0.01606,-0.01606,0.01557,-0.01646,0.01500,-0.01676,0.01437,-0.01694,0.01369,-0.01700,0.01300,-0.01700,-0.01300,-0.01694,-0.01370,-0.01676,-0.01437,-0.01646,-0.01500,-0.01606,-0.01557,-0.01557,-0.01606,-0.01500,-0.01646,-0.01437,-0.01676,-0.01370,-0.01694,-0.01300,-0.01700,0.01300,-0.01700,0.01369,-0.01694,0.01437,-0.01676,0.01500,-0.01646,0.01557,-0.01606,0.01606,-0.01557,0.01646,-0.01500,0.01676,-0.01437,0.01694,-0.01370,0.01700,-0.01300,0.01700,0.01300,0.01694,0.01369,0.01676,0.01437,0.01646,0.01500,0.01606,0.01557,0.01557,0.01606,0.01500,0.01646,0.01437,0.01676,0.01369,0.01694,0.01300,0.01700,0.00000*
%
%AMMACRO18_180*
4,1,40,-0.00700,-0.01100,0.00700,-0.01100,0.00769,-0.01094,0.00837,-0.01076,0.00900,-0.01046,0.00957,-0.01006,0.01006,-0.00957,0.01046,-0.00900,0.01076,-0.00837,0.01094,-0.00770,0.01100,-0.00700,0.01100,0.00700,0.01094,0.00769,0.01076,0.00837,0.01046,0.00900,0.01006,0.00957,0.00957,0.01006,0.00900,0.01046,0.00837,0.01076,0.00769,0.01094,0.00700,0.01100,-0.00700,0.01100,-0.00770,0.01094,-0.00837,0.01076,-0.00900,0.01046,-0.00957,0.01006,-0.01006,0.00957,-0.01046,0.00900,-0.01076,0.00837,-0.01094,0.00769,-0.01100,0.00700,-0.01100,-0.00700,-0.01094,-0.00770,-0.01076,-0.00837,-0.01046,-0.00900,-0.01006,-0.00957,-0.00957,-0.01006,-0.00900,-0.01046,-0.00837,-0.01076,-0.00770,-0.01094,-0.00700,-0.01100,0.00000*
%
%AMMACRO37_180*
4,1,40,-0.01200,0.00800,-0.01200,-0.00800,-0.01194,-0.00870,-0.01176,-0.00937,-0.01146,-0.01000,-0.01106,-0.01057,-0.01057,-0.01106,-0.01000,-0.01146,-0.00937,-0.01176,-0.00870,-0.01194,-0.00800,-0.01200,0.00800,-0.01200,0.00869,-0.01194,0.00937,-0.01176,0.01000,-0.01146,0.01057,-0.01106,0.01106,-0.01057,0.01146,-0.01000,0.01176,-0.00937,0.01194,-0.00870,0.01200,-0.00800,0.01200,0.00800,0.01194,0.00869,0.01176,0.00937,0.01146,0.01000,0.01106,0.01057,0.01057,0.01106,0.01000,0.01146,0.00937,0.01176,0.00869,0.01194,0.00800,0.01200,-0.00800,0.01200,-0.00870,0.01194,-0.00937,0.01176,-0.01000,0.01146,-0.01057,0.01106,-0.01106,0.01057,-0.01146,0.01000,-0.01176,0.00937,-0.01194,0.00869,-0.01200,0.00800,0.00000*
%
%AMMACRO19_180*
4,1,40,0.01100,-0.00700,0.01100,0.00700,0.01094,0.00769,0.01076,0.00837,0.01046,0.00900,0.01006,0.00957,0.00957,0.01006,0.00900,0.01046,0.00837,0.01076,0.00769,0.01094,0.00700,0.01100,-0.00700,0.01100,-0.00770,0.01094,-0.00837,0.01076,-0.00900,0.01046,-0.00957,0.01006,-0.01006,0.00957,-0.01046,0.00900,-0.01076,0.00837,-0.01094,0.00769,-0.01100,0.00700,-0.01100,-0.00700,-0.01094,-0.00770,-0.01076,-0.00837,-0.01046,-0.00900,-0.01006,-0.00957,-0.00957,-0.01006,-0.00900,-0.01046,-0.00837,-0.01076,-0.00770,-0.01094,-0.00700,-0.01100,0.00700,-0.01100,0.00769,-0.01094,0.00837,-0.01076,0.00900,-0.01046,0.00957,-0.01006,0.01006,-0.00957,0.01046,-0.00900,0.01076,-0.00837,0.01094,-0.00770,0.01100,-0.00700,0.00000*
%
%AMMACRO28_180*
4,1,40,0.00800,0.01200,-0.00800,0.01200,-0.00870,0.01194,-0.00937,0.01176,-0.01000,0.01146,-0.01057,0.01106,-0.01106,0.01057,-0.01146,0.01000,-0.01176,0.00937,-0.01194,0.00869,-0.01200,0.00800,-0.01200,-0.00800,-0.01194,-0.00870,-0.01176,-0.00937,-0.01146,-0.01000,-0.01106,-0.01057,-0.01057,-0.01106,-0.01000,-0.01146,-0.00937,-0.01176,-0.00870,-0.01194,-0.00800,-0.01200,0.00800,-0.01200,0.00869,-0.01194,0.00937,-0.01176,0.01000,-0.01146,0.01057,-0.01106,0.01106,-0.01057,0.01146,-0.01000,0.01176,-0.00937,0.01194,-0.00870,0.01200,-0.00800,0.01200,0.00800,0.01194,0.00869,0.01176,0.00937,0.01146,0.01000,0.01106,0.01057,0.01057,0.01106,0.01000,0.01146,0.00937,0.01176,0.00869,0.01194,0.00800,0.01200,0.00000*
%
%AMMACRO82_180*
4,1,40,0.01400,0.00800,0.01400,-0.00800,0.01394,-0.00870,0.01376,-0.00937,0.01346,-0.01000,0.01306,-0.01057,0.01257,-0.01106,0.01200,-0.01146,0.01137,-0.01176,0.01069,-0.01194,0.01000,-0.01200,-0.01000,-0.01200,-0.01070,-0.01194,-0.01137,-0.01176,-0.01200,-0.01146,-0.01257,-0.01106,-0.01306,-0.01057,-0.01346,-0.01000,-0.01376,-0.00937,-0.01394,-0.00870,-0.01400,-0.00800,-0.01400,0.00800,-0.01394,0.00869,-0.01376,0.00937,-0.01346,0.01000,-0.01306,0.01057,-0.01257,0.01106,-0.01200,0.01146,-0.01137,0.01176,-0.01070,0.01194,-0.01000,0.01200,0.01000,0.01200,0.01069,0.01194,0.01137,0.01176,0.01200,0.01146,0.01257,0.01106,0.01306,0.01057,0.01346,0.01000,0.01376,0.00937,0.01394,0.00869,0.01400,0.00800,0.00000*
%
%AMMACRO65_180*
4,1,25,-0.26969,0.01299,-0.26969,0.83465,0.26969,0.83465,0.26969,-0.83465,-0.26969,-0.83465,-0.26969,-0.12087,-0.22638,-0.12087,-0.21476,-0.11985,-0.20349,-0.11683,-0.19292,-0.11190,-0.18336,-0.10521,-0.17511,-0.09696,-0.16842,-0.08741,-0.16349,-0.07683,-0.16047,-0.06556,-0.15945,-0.05394,-0.16047,-0.04232,-0.16349,-0.03105,-0.16842,-0.02048,-0.17511,-0.01092,-0.18336,-0.00267,-0.19292,0.00402,-0.20349,0.00895,-0.21476,0.01197,-0.22638,0.01299,-0.26969,0.01299,0.00000*
%
%AMMACRO38_180*
4,1,40,-0.01200,0.00800,-0.01200,-0.00800,-0.01194,-0.00870,-0.01176,-0.00937,-0.01146,-0.01000,-0.01106,-0.01057,-0.01057,-0.01106,-0.01000,-0.01146,-0.00937,-0.01176,-0.00870,-0.01194,-0.00800,-0.01200,0.00800,-0.01200,0.00869,-0.01194,0.00937,-0.01176,0.01000,-0.01146,0.01057,-0.01106,0.01106,-0.01057,0.01146,-0.01000,0.01176,-0.00937,0.01194,-0.00870,0.01200,-0.00800,0.01200,0.00800,0.01194,0.00869,0.01176,0.00937,0.01146,0.01000,0.01106,0.01057,0.01057,0.01106,0.01000,0.01146,0.00937,0.01176,0.00869,0.01194,0.00800,0.01200,-0.00800,0.01200,-0.00870,0.01194,-0.00937,0.01176,-0.01000,0.01146,-0.01057,0.01106,-0.01106,0.01057,-0.01146,0.01000,-0.01176,0.00937,-0.01194,0.00869,-0.01200,0.00800,0.00000*
%
%AMMACRO84_180*
4,1,40,-0.00700,-0.02250,-0.00839,-0.02238,-0.00974,-0.02202,-0.01100,-0.02143,-0.01214,-0.02063,-0.01313,-0.01964,-0.01393,-0.01850,-0.01452,-0.01724,-0.01488,-0.01589,-0.01500,-0.01450,-0.01500,0.01450,-0.01488,0.01589,-0.01452,0.01724,-0.01393,0.01850,-0.01313,0.01964,-0.01214,0.02063,-0.01100,0.02143,-0.00974,0.02202,-0.00839,0.02238,-0.00700,0.02250,0.00700,0.02250,0.00839,0.02238,0.00974,0.02202,0.01100,0.02143,0.01214,0.02063,0.01313,0.01964,0.01393,0.01850,0.01452,0.01724,0.01488,0.01589,0.01500,0.01450,0.01500,-0.01450,0.01488,-0.01589,0.01452,-0.01724,0.01393,-0.01850,0.01313,-0.01964,0.01214,-0.02063,0.01100,-0.02143,0.00974,-0.02202,0.00839,-0.02238,0.00700,-0.02250,-0.00700,-0.02250,0.00000*
%
%AMMACRO66_180*
4,1,40,0.01200,-0.00800,0.01200,0.00800,0.01194,0.00869,0.01176,0.00937,0.01146,0.01000,0.01106,0.01057,0.01057,0.01106,0.01000,0.01146,0.00937,0.01176,0.00869,0.01194,0.00800,0.01200,-0.00800,0.01200,-0.00870,0.01194,-0.00937,0.01176,-0.01000,0.01146,-0.01057,0.01106,-0.01106,0.01057,-0.01146,0.01000,-0.01176,0.00937,-0.01194,0.00869,-0.01200,0.00800,-0.01200,-0.00800,-0.01194,-0.00870,-0.01176,-0.00937,-0.01146,-0.01000,-0.01106,-0.01057,-0.01057,-0.01106,-0.01000,-0.01146,-0.00937,-0.01176,-0.00870,-0.01194,-0.00800,-0.01200,0.00800,-0.01200,0.00869,-0.01194,0.00937,-0.01176,0.01000,-0.01146,0.01057,-0.01106,0.01106,-0.01057,0.01146,-0.01000,0.01176,-0.00937,0.01194,-0.00870,0.01200,-0.00800,0.00000*
%
%AMMACRO75_180*
4,1,40,0.00700,0.02250,0.00839,0.02238,0.00974,0.02202,0.01100,0.02143,0.01214,0.02063,0.01313,0.01964,0.01393,0.01850,0.01452,0.01724,0.01488,0.01589,0.01500,0.01450,0.01500,-0.01450,0.01488,-0.01589,0.01452,-0.01724,0.01393,-0.01850,0.01313,-0.01964,0.01214,-0.02063,0.01100,-0.02143,0.00974,-0.02202,0.00839,-0.02238,0.00700,-0.02250,-0.00700,-0.02250,-0.00839,-0.02238,-0.00974,-0.02202,-0.01100,-0.02143,-0.01214,-0.02063,-0.01313,-0.01964,-0.01393,-0.01850,-0.01452,-0.01724,-0.01488,-0.01589,-0.01500,-0.01450,-0.01500,0.01450,-0.01488,0.01589,-0.01452,0.01724,-0.01393,0.01850,-0.01313,0.01964,-0.01214,0.02063,-0.01100,0.02143,-0.00974,0.02202,-0.00839,0.02238,-0.00700,0.02250,0.00700,0.02250,0.00000*
%
%AMMACRO49_180*
4,1,40,0.01700,-0.01300,0.01700,0.01300,0.01694,0.01369,0.01676,0.01437,0.01646,0.01500,0.01606,0.01557,0.01557,0.01606,0.01500,0.01646,0.01437,0.01676,0.01369,0.01694,0.01300,0.01700,-0.01300,0.01700,-0.01370,0.01694,-0.01437,0.01676,-0.01500,0.01646,-0.01557,0.01606,-0.01606,0.01557,-0.01646,0.01500,-0.01676,0.01437,-0.01694,0.01369,-0.01700,0.01300,-0.01700,-0.01300,-0.01694,-0.01370,-0.01676,-0.01437,-0.01646,-0.01500,-0.01606,-0.01557,-0.01557,-0.01606,-0.01500,-0.01646,-0.01437,-0.01676,-0.01370,-0.01694,-0.01300,-0.01700,0.01300,-0.01700,0.01369,-0.01694,0.01437,-0.01676,0.01500,-0.01646,0.01557,-0.01606,0.01606,-0.01557,0.01646,-0.01500,0.01676,-0.01437,0.01694,-0.01370,0.01700,-0.01300,0.00000*
%
%AMMACRO67_180*
4,1,40,0.01200,-0.00800,0.01200,0.00800,0.01194,0.00869,0.01176,0.00937,0.01146,0.01000,0.01106,0.01057,0.01057,0.01106,0.01000,0.01146,0.00937,0.01176,0.00869,0.01194,0.00800,0.01200,-0.00800,0.01200,-0.00870,0.01194,-0.00937,0.01176,-0.01000,0.01146,-0.01057,0.01106,-0.01106,0.01057,-0.01146,0.01000,-0.01176,0.00937,-0.01194,0.00869,-0.01200,0.00800,-0.01200,-0.00800,-0.01194,-0.00870,-0.01176,-0.00937,-0.01146,-0.01000,-0.01106,-0.01057,-0.01057,-0.01106,-0.01000,-0.01146,-0.00937,-0.01176,-0.00870,-0.01194,-0.00800,-0.01200,0.00800,-0.01200,0.00869,-0.01194,0.00937,-0.01176,0.01000,-0.01146,0.01057,-0.01106,0.01106,-0.01057,0.01146,-0.01000,0.01176,-0.00937,0.01194,-0.00870,0.01200,-0.00800,0.00000*
%
%AMMACRO79_180*
4,1,25,0.26969,0.01299,0.26969,0.83465,-0.26969,0.83465,-0.26969,-0.83465,0.26969,-0.83465,0.26969,-0.12087,0.22638,-0.12087,0.21476,-0.11985,0.20349,-0.11683,0.19291,-0.11190,0.18336,-0.10521,0.17511,-0.09696,0.16842,-0.08741,0.16349,-0.07683,0.16047,-0.06556,0.15945,-0.05394,0.16047,-0.04232,0.16349,-0.03105,0.16842,-0.02048,0.17511,-0.01092,0.18336,-0.00267,0.19291,0.00402,0.20349,0.00895,0.21476,0.01197,0.22638,0.01299,0.26969,0.01299,0.00000*
%
%ADD10C,0.14000*%
%ADD11R,0.16000X0.16000*%
%ADD12C,0.14200*%
%ADD13C,0.05600*%
%ADD14C,0.31500*%
%ADD15C,0.05000*%
%ADD16C,0.02800*%
%ADD17C,0.11500*%
%ADD18C,0.12600*%
%ADD19C,0.09900*%
%ADD71C,0.03200*%
%ADD20C,0.05700*%
%ADD21C,0.37500*%
%ADD23C,0.02000*%
%ADD24C,0.00600*%
%ADD28MACRO18*%
%ADD29MACRO26*%
%ADD72R,0.03000X0.04500*%
%ADD73R,0.01400X0.06000*%
%ADD30R,0.08000X0.07100*%
%ADD31MACRO31*%
%ADD32R,0.04500X0.03000*%
%ADD33R,0.08000X0.12700*%
%ADD34R,0.05000X0.06500*%
%ADD35MACRO35*%
%ADD36MACRO36*%
%ADD37R,0.06500X0.02500*%
%ADD38R,0.05500X0.03500*%
%ADD39R,0.08700X0.20800*%
%ADD40MACRO40*%
%ADD41MACRO41*%
%ADD42MACRO42*%
%ADD43MACRO43*%
%ADD44MACRO44*%
%ADD45C,0.11500*%
%ADD46C,0.12600*%
%ADD47C,0.09900*%
%ADD48C,0.05700*%
%ADD49MACRO49*%
%ADD50MACRO50*%
%ADD51R,0.08500X0.12800*%
%ADD52R,0.03000X0.06400*%
%ADD53R,0.13500X0.10100*%
%ADD54R,0.01200X0.06000*%
%ADD55C,0.03200*%
%ADD56R,0.20800X0.08700*%
%ADD57R,0.04800X0.01600*%
%ADD58R,0.06500X0.05000*%
%ADD59R,0.05500X0.04500*%
%ADD60R,0.04000X0.02300*%
%ADD61R,0.03500X0.05500*%
%ADD62R,0.04500X0.05500*%
%ADD63R,0.01600X0.04800*%
%ADD64R,0.09000X0.04500*%
%ADD65R,0.09000X0.09500*%
%ADD66MACRO66*%
%ADD67MACRO67*%
%ADD68C,0.37500*%
%ADD69R,0.06000X0.01200*%
%ADD74R,0.04000X0.01600*%
%ADD75MACRO75*%
%ADD76R,0.01600X0.04500*%
%ADD77R,0.04500X0.01600*%
%ADD78R,0.12200X0.12200*%
%ADD79MACRO79*%
%ADD80R,0.12000X0.12000*%
%ADD81R,0.07100X0.06300*%
%ADD82MACRO82*%
%ADD83R,0.03000X0.04600*%
%ADD84MACRO84*%
%ADD85R,0.02200X0.04000*%
%ADD86R,0.09500X0.09000*%
%ADD87R,0.05900X0.08900*%
%ADD88MACRO38*%
%ADD89MACRO28*%
%ADD90MACRO24*%
%ADD91MACRO19*%
%ADD92MACRO30*%
%ADD93MACRO17*%
%ADD94MACRO65*%
%ADD95MACRO37*%
%ADD96MACRO27*%
%ADD97MACRO21*%
%ADD98MACRO20*%
%ADD202R,0.12000X0.12000*%
%ADD204MACRO20_180*%
%ADD205MACRO21_180*%
%ADD206MACRO30_180*%
%ADD207R,0.03000X0.04500*%
%ADD208MACRO31_180*%
%ADD209MACRO40_180*%
%ADD210R,0.04500X0.03000*%
%ADD211MACRO50_180*%
%ADD212MACRO41_180*%
%ADD213MACRO24_180*%
%ADD214R,0.04000X0.02300*%
%ADD215MACRO42_180*%
%ADD216R,0.08500X0.12800*%
%ADD217R,0.08000X0.12700*%
%ADD218R,0.09000X0.09500*%
%ADD219R,0.05500X0.04500*%
%ADD220R,0.03500X0.05500*%
%ADD221R,0.05500X0.03500*%
%ADD222R,0.05000X0.06500*%
%ADD223R,0.03000X0.06400*%
%ADD224MACRO43_180*%
%ADD225MACRO17_180*%
%ADD226R,0.04500X0.05500*%
%ADD227R,0.06500X0.02500*%
%ADD228R,0.13500X0.10100*%
%ADD229MACRO26_180*%
%ADD230MACRO35_180*%
%ADD231MACRO44_180*%
%ADD232MACRO27_180*%
%ADD233R,0.09500X0.09000*%
%ADD234R,0.07100X0.06300*%
%ADD235R,0.08000X0.07100*%
%ADD236R,0.01200X0.06000*%
%ADD237MACRO36_180*%
%ADD238MACRO18_180*%
%ADD239MACRO37_180*%
%ADD240MACRO19_180*%
%ADD241MACRO28_180*%
%ADD242R,0.09000X0.04500*%
%ADD243R,0.01400X0.06000*%
%ADD244MACRO82_180*%
%ADD245MACRO65_180*%
%ADD246MACRO38_180*%
%ADD247R,0.04800X0.01600*%
%ADD248R,0.03000X0.04600*%
%ADD249R,0.04000X0.01600*%
%ADD250R,0.20800X0.08700*%
%ADD251MACRO84_180*%
%ADD252R,0.01600X0.04800*%
%ADD253MACRO66_180*%
%ADD254MACRO75_180*%
%ADD255R,0.08700X0.20800*%
%ADD256R,0.06500X0.05000*%
%ADD257R,0.01600X0.04500*%
%ADD258R,0.02200X0.04000*%
%ADD259MACRO49_180*%
%ADD260MACRO67_180*%
%ADD261R,0.05900X0.08900*%
%ADD262R,0.04500X0.01600*%
%ADD263R,0.12200X0.12200*%
%ADD264R,0.06000X0.01200*%
%ADD265MACRO79_180*%
%LNTMASK.art*%
%LPD*%
G36*
X533489Y686015D02*
G01Y692015D01*
X537689*
Y686015*
X533489*
G37*
G36*
Y677815D02*
G01Y683815D01*
X537689*
Y677815*
X533489*
G37*
G36*
X527089Y686015D02*
G01Y692015D01*
X531289*
Y686015*
X527089*
G37*
G36*
Y677815D02*
G01Y683815D01*
X531289*
Y677815*
X527089*
G37*
G36*
X319104Y1284689D02*
G01Y1290689D01*
X323304*
Y1284689*
X319104*
G37*
G36*
Y1276489D02*
G01Y1282489D01*
X323304*
Y1276489*
X319104*
G37*
G36*
X312704Y1284689D02*
G01Y1290689D01*
X316904*
Y1284689*
X312704*
G37*
G36*
Y1276489D02*
G01Y1282489D01*
X316904*
Y1276489*
X312704*
G37*
G36*
X104356Y686015D02*
G01Y692015D01*
X108556*
Y686015*
X104356*
G37*
G36*
Y677815D02*
G01Y683815D01*
X108556*
Y677815*
X104356*
G37*
G36*
X97956Y686015D02*
G01Y692015D01*
X102156*
Y686015*
X97956*
G37*
G36*
Y677815D02*
G01Y683815D01*
X102156*
Y677815*
X97956*
G37*
G36*
X-110030Y1284689D02*
G01Y1290689D01*
X-105830*
Y1284689*
X-110030*
G37*
G36*
Y1276489D02*
G01Y1282489D01*
X-105830*
Y1276489*
X-110030*
G37*
G36*
X-116430Y1284689D02*
G01Y1290689D01*
X-112230*
Y1284689*
X-116430*
G37*
G36*
Y1276489D02*
G01Y1282489D01*
X-112230*
Y1276489*
X-116430*
G37*
G36*
X606933Y455365D02*
G01Y464315D01*
X615483*
Y455365*
X606933*
G37*
G36*
Y443815D02*
G01Y452765D01*
X615483*
Y443815*
X606933*
G37*
G36*
X600433Y1591365D02*
G01Y1600315D01*
X608983*
Y1591365*
X600433*
G37*
G36*
Y1579815D02*
G01Y1588765D01*
X608983*
Y1579815*
X600433*
G37*
G36*
X595783Y455365D02*
G01Y464315D01*
X604333*
Y455365*
X595783*
G37*
G36*
Y443815D02*
G01Y452765D01*
X604333*
Y443815*
X595783*
G37*
G36*
X589283Y1591365D02*
G01Y1600315D01*
X597833*
Y1591365*
X589283*
G37*
G36*
Y1579815D02*
G01Y1588765D01*
X597833*
Y1579815*
X589283*
G37*
G36*
X578933Y455365D02*
G01Y464315D01*
X587483*
Y455365*
X578933*
G37*
G36*
Y443815D02*
G01Y452765D01*
X587483*
Y443815*
X578933*
G37*
G36*
X567783Y455365D02*
G01Y464315D01*
X576333*
Y455365*
X567783*
G37*
G36*
Y443815D02*
G01Y452765D01*
X576333*
Y443815*
X567783*
G37*
G36*
X566433Y1591365D02*
G01Y1600315D01*
X574983*
Y1591365*
X566433*
G37*
G36*
Y1579815D02*
G01Y1588765D01*
X574983*
Y1579815*
X566433*
G37*
G36*
X555283Y1591365D02*
G01Y1600315D01*
X563833*
Y1591365*
X555283*
G37*
G36*
Y1579815D02*
G01Y1588765D01*
X563833*
Y1579815*
X555283*
G37*
G36*
X534433Y455365D02*
G01Y464315D01*
X542983*
Y455365*
X534433*
G37*
G36*
Y443815D02*
G01Y452765D01*
X542983*
Y443815*
X534433*
G37*
G36*
X531433Y1591365D02*
G01Y1600315D01*
X539983*
Y1591365*
X531433*
G37*
G36*
Y1579815D02*
G01Y1588765D01*
X539983*
Y1579815*
X531433*
G37*
G36*
X523283Y455365D02*
G01Y464315D01*
X531833*
Y455365*
X523283*
G37*
G36*
Y443815D02*
G01Y452765D01*
X531833*
Y443815*
X523283*
G37*
G36*
X520283Y1591365D02*
G01Y1600315D01*
X528833*
Y1591365*
X520283*
G37*
G36*
Y1579815D02*
G01Y1588765D01*
X528833*
Y1579815*
X520283*
G37*
G36*
X506933Y455865D02*
G01Y464815D01*
X515483*
Y455865*
X506933*
G37*
G36*
Y444315D02*
G01Y453265D01*
X515483*
Y444315*
X506933*
G37*
G36*
X498333Y1591465D02*
G01Y1600415D01*
X506883*
Y1591465*
X498333*
G37*
G36*
Y1579915D02*
G01Y1588865D01*
X506883*
Y1579915*
X498333*
G37*
G36*
X495783Y455865D02*
G01Y464815D01*
X504333*
Y455865*
X495783*
G37*
G36*
Y444315D02*
G01Y453265D01*
X504333*
Y444315*
X495783*
G37*
G36*
X487183Y1591465D02*
G01Y1600415D01*
X495733*
Y1591465*
X487183*
G37*
G36*
Y1579915D02*
G01Y1588865D01*
X495733*
Y1579915*
X487183*
G37*
G36*
X354660Y379639D02*
G01Y388589D01*
X363210*
Y379639*
X354660*
G37*
G36*
Y368089D02*
G01Y377039D01*
X363210*
Y368089*
X354660*
G37*
G36*
X346060Y1515239D02*
G01Y1524189D01*
X354610*
Y1515239*
X346060*
G37*
G36*
Y1503689D02*
G01Y1512639D01*
X354610*
Y1503689*
X346060*
G37*
G36*
X343510Y379639D02*
G01Y388589D01*
X352060*
Y379639*
X343510*
G37*
G36*
Y368089D02*
G01Y377039D01*
X352060*
Y368089*
X343510*
G37*
G36*
X334910Y1515239D02*
G01Y1524189D01*
X343460*
Y1515239*
X334910*
G37*
G36*
Y1503689D02*
G01Y1512639D01*
X343460*
Y1503689*
X334910*
G37*
G36*
X321560Y379739D02*
G01Y388689D01*
X330110*
Y379739*
X321560*
G37*
G36*
Y368189D02*
G01Y377139D01*
X330110*
Y368189*
X321560*
G37*
G36*
X318560Y1515739D02*
G01Y1524689D01*
X327110*
Y1515739*
X318560*
G37*
G36*
Y1504189D02*
G01Y1513139D01*
X327110*
Y1504189*
X318560*
G37*
G36*
X310410Y379739D02*
G01Y388689D01*
X318960*
Y379739*
X310410*
G37*
G36*
Y368189D02*
G01Y377139D01*
X318960*
Y368189*
X310410*
G37*
G36*
X307410Y1515739D02*
G01Y1524689D01*
X315960*
Y1515739*
X307410*
G37*
G36*
Y1504189D02*
G01Y1513139D01*
X315960*
Y1504189*
X307410*
G37*
G36*
X286560Y379739D02*
G01Y388689D01*
X295110*
Y379739*
X286560*
G37*
G36*
Y368189D02*
G01Y377139D01*
X295110*
Y368189*
X286560*
G37*
G36*
X275410Y379739D02*
G01Y388689D01*
X283960*
Y379739*
X275410*
G37*
G36*
Y368189D02*
G01Y377139D01*
X283960*
Y368189*
X275410*
G37*
G36*
X274060Y1515739D02*
G01Y1524689D01*
X282610*
Y1515739*
X274060*
G37*
G36*
Y1504189D02*
G01Y1513139D01*
X282610*
Y1504189*
X274060*
G37*
G36*
X262910Y1515739D02*
G01Y1524689D01*
X271460*
Y1515739*
X262910*
G37*
G36*
Y1504189D02*
G01Y1513139D01*
X271460*
Y1504189*
X262910*
G37*
G36*
X252560Y379739D02*
G01Y388689D01*
X261110*
Y379739*
X252560*
G37*
G36*
Y368189D02*
G01Y377139D01*
X261110*
Y368189*
X252560*
G37*
G36*
X246060Y1515739D02*
G01Y1524689D01*
X254610*
Y1515739*
X246060*
G37*
G36*
Y1504189D02*
G01Y1513139D01*
X254610*
Y1504189*
X246060*
G37*
G36*
X241410Y379739D02*
G01Y388689D01*
X249960*
Y379739*
X241410*
G37*
G36*
Y368189D02*
G01Y377139D01*
X249960*
Y368189*
X241410*
G37*
G36*
X234910Y1515739D02*
G01Y1524689D01*
X243460*
Y1515739*
X234910*
G37*
G36*
Y1504189D02*
G01Y1513139D01*
X243460*
Y1504189*
X234910*
G37*
G36*
X177800Y455365D02*
G01Y464315D01*
X186350*
Y455365*
X177800*
G37*
G36*
Y443815D02*
G01Y452765D01*
X186350*
Y443815*
X177800*
G37*
G36*
X171300Y1591365D02*
G01Y1600315D01*
X179850*
Y1591365*
X171300*
G37*
G36*
Y1579815D02*
G01Y1588765D01*
X179850*
Y1579815*
X171300*
G37*
G36*
X166650Y455365D02*
G01Y464315D01*
X175200*
Y455365*
X166650*
G37*
G36*
Y443815D02*
G01Y452765D01*
X175200*
Y443815*
X166650*
G37*
G36*
X160150Y1591365D02*
G01Y1600315D01*
X168700*
Y1591365*
X160150*
G37*
G36*
Y1579815D02*
G01Y1588765D01*
X168700*
Y1579815*
X160150*
G37*
G36*
X149800Y455365D02*
G01Y464315D01*
X158350*
Y455365*
X149800*
G37*
G36*
Y443815D02*
G01Y452765D01*
X158350*
Y443815*
X149800*
G37*
G36*
X138650Y455365D02*
G01Y464315D01*
X147200*
Y455365*
X138650*
G37*
G36*
Y443815D02*
G01Y452765D01*
X147200*
Y443815*
X138650*
G37*
G36*
X137300Y1591365D02*
G01Y1600315D01*
X145850*
Y1591365*
X137300*
G37*
G36*
Y1579815D02*
G01Y1588765D01*
X145850*
Y1579815*
X137300*
G37*
G36*
X126150Y1591365D02*
G01Y1600315D01*
X134700*
Y1591365*
X126150*
G37*
G36*
Y1579815D02*
G01Y1588765D01*
X134700*
Y1579815*
X126150*
G37*
G36*
X105300Y455365D02*
G01Y464315D01*
X113850*
Y455365*
X105300*
G37*
G36*
Y443815D02*
G01Y452765D01*
X113850*
Y443815*
X105300*
G37*
G36*
X102300Y1591365D02*
G01Y1600315D01*
X110850*
Y1591365*
X102300*
G37*
G36*
Y1579815D02*
G01Y1588765D01*
X110850*
Y1579815*
X102300*
G37*
G36*
X94150Y455365D02*
G01Y464315D01*
X102700*
Y455365*
X94150*
G37*
G36*
Y443815D02*
G01Y452765D01*
X102700*
Y443815*
X94150*
G37*
G36*
X91150Y1591365D02*
G01Y1600315D01*
X99700*
Y1591365*
X91150*
G37*
G36*
Y1579815D02*
G01Y1588765D01*
X99700*
Y1579815*
X91150*
G37*
G36*
X77800Y455865D02*
G01Y464815D01*
X86350*
Y455865*
X77800*
G37*
G36*
Y444315D02*
G01Y453265D01*
X86350*
Y444315*
X77800*
G37*
G36*
X69200Y1591465D02*
G01Y1600415D01*
X77750*
Y1591465*
X69200*
G37*
G36*
Y1579915D02*
G01Y1588865D01*
X77750*
Y1579915*
X69200*
G37*
G36*
X66650Y455865D02*
G01Y464815D01*
X75200*
Y455865*
X66650*
G37*
G36*
Y444315D02*
G01Y453265D01*
X75200*
Y444315*
X66650*
G37*
G36*
X58050Y1591465D02*
G01Y1600415D01*
X66600*
Y1591465*
X58050*
G37*
G36*
Y1579915D02*
G01Y1588865D01*
X66600*
Y1579915*
X58050*
G37*
G36*
X-74474Y379639D02*
G01Y388589D01*
X-65924*
Y379639*
X-74474*
G37*
G36*
Y368089D02*
G01Y377039D01*
X-65924*
Y368089*
X-74474*
G37*
G36*
X-83074Y1515239D02*
G01Y1524189D01*
X-74524*
Y1515239*
X-83074*
G37*
G36*
Y1503689D02*
G01Y1512639D01*
X-74524*
Y1503689*
X-83074*
G37*
G36*
X-85624Y379639D02*
G01Y388589D01*
X-77074*
Y379639*
X-85624*
G37*
G36*
Y368089D02*
G01Y377039D01*
X-77074*
Y368089*
X-85624*
G37*
G36*
X-94224Y1515239D02*
G01Y1524189D01*
X-85674*
Y1515239*
X-94224*
G37*
G36*
Y1503689D02*
G01Y1512639D01*
X-85674*
Y1503689*
X-94224*
G37*
G36*
X-107574Y379739D02*
G01Y388689D01*
X-99024*
Y379739*
X-107574*
G37*
G36*
Y368189D02*
G01Y377139D01*
X-99024*
Y368189*
X-107574*
G37*
G36*
X-110574Y1515739D02*
G01Y1524689D01*
X-102024*
Y1515739*
X-110574*
G37*
G36*
Y1504189D02*
G01Y1513139D01*
X-102024*
Y1504189*
X-110574*
G37*
G36*
X-118724Y379739D02*
G01Y388689D01*
X-110174*
Y379739*
X-118724*
G37*
G36*
Y368189D02*
G01Y377139D01*
X-110174*
Y368189*
X-118724*
G37*
G36*
X-121724Y1515739D02*
G01Y1524689D01*
X-113174*
Y1515739*
X-121724*
G37*
G36*
Y1504189D02*
G01Y1513139D01*
X-113174*
Y1504189*
X-121724*
G37*
G36*
X-142574Y379739D02*
G01Y388689D01*
X-134024*
Y379739*
X-142574*
G37*
G36*
Y368189D02*
G01Y377139D01*
X-134024*
Y368189*
X-142574*
G37*
G36*
X-153724Y379739D02*
G01Y388689D01*
X-145174*
Y379739*
X-153724*
G37*
G36*
Y368189D02*
G01Y377139D01*
X-145174*
Y368189*
X-153724*
G37*
G36*
X-155074Y1515739D02*
G01Y1524689D01*
X-146524*
Y1515739*
X-155074*
G37*
G36*
Y1504189D02*
G01Y1513139D01*
X-146524*
Y1504189*
X-155074*
G37*
G36*
X-166224Y1515739D02*
G01Y1524689D01*
X-157674*
Y1515739*
X-166224*
G37*
G36*
Y1504189D02*
G01Y1513139D01*
X-157674*
Y1504189*
X-166224*
G37*
G36*
X-176574Y379739D02*
G01Y388689D01*
X-168024*
Y379739*
X-176574*
G37*
G36*
Y368189D02*
G01Y377139D01*
X-168024*
Y368189*
X-176574*
G37*
G36*
X-183074Y1515739D02*
G01Y1524689D01*
X-174524*
Y1515739*
X-183074*
G37*
G36*
Y1504189D02*
G01Y1513139D01*
X-174524*
Y1504189*
X-183074*
G37*
G36*
X-187724Y379739D02*
G01Y388689D01*
X-179174*
Y379739*
X-187724*
G37*
G36*
Y368189D02*
G01Y377139D01*
X-179174*
Y368189*
X-187724*
G37*
G36*
X-194224Y1515739D02*
G01Y1524689D01*
X-185674*
Y1515739*
X-194224*
G37*
G36*
Y1504189D02*
G01Y1513139D01*
X-185674*
Y1504189*
X-194224*
G37*
G54D10*
X-222440Y19685D03*
Y1948818D03*
X643700Y19685D03*
Y1948818D03*
G54D98*
X32700Y256900D03*
X19283Y310682D03*
X32900Y1664200D03*
X25900Y1725100D03*
X56600Y195000D03*
X57400Y211300D03*
X56900Y240000D03*
X63000Y267700D03*
X39200Y347200D03*
X81400Y533900D03*
X78400Y591000D03*
X49600Y576900D03*
X61400Y676800D03*
X57400D03*
X64100Y912800D03*
X77002Y1137897D03*
X83500Y1465200D03*
X96100Y533900D03*
X124900Y588604D03*
X120800D03*
X93065Y597471D03*
X97265D03*
X92465Y610371D03*
X95200Y665700D03*
X110900Y884800D03*
X102600D03*
X119300D03*
X122529Y955744D03*
X117529D03*
X112529D03*
X135000Y1411804D03*
X134700Y1404004D03*
X100500Y1423700D03*
X91500D03*
X105000D03*
X107500Y1490200D03*
X170600Y532500D03*
X155600Y532400D03*
X158000Y578600D03*
X170200Y627100D03*
X180365Y645771D03*
X137765Y662071D03*
X154500Y687200D03*
X149500Y711700D03*
X147900Y1003100D03*
X152100Y1003200D03*
X163500Y997700D03*
X159500D03*
X143800Y1003200D03*
X137500Y1443700D03*
G54D11*
X-181139Y20007D03*
X-180444Y1947256D03*
X601704Y21248D03*
X602399Y1948497D03*
G54D97*
X32800Y272300D03*
X29100Y321300D03*
X30100Y1083600D03*
X18600Y1644300D03*
X18400Y1720700D03*
X20200Y1692800D03*
X85800Y71500D03*
X56900Y155300D03*
Y163300D03*
Y179300D03*
Y159300D03*
Y175300D03*
X46500Y213400D03*
X57800Y217000D03*
X56900Y199300D03*
X70800Y431300D03*
X61000Y577200D03*
X78556Y690465D03*
X80700Y686400D03*
X83996Y848500D03*
Y844100D03*
Y852900D03*
X84000Y857200D03*
Y865700D03*
Y861500D03*
X45400Y916400D03*
X68700Y999800D03*
X84300Y1484000D03*
X49400Y1769800D03*
X88303Y61502D03*
X117900Y437500D03*
X125956Y692165D03*
X125856Y688065D03*
Y683665D03*
X112900Y670600D03*
X111900Y1408200D03*
X91300Y1451000D03*
X109700Y1425900D03*
X91300Y1439000D03*
X128800Y1482000D03*
X159900Y545600D03*
X162700Y622700D03*
X152329Y615065D03*
X171800Y701100D03*
X152096Y1419200D03*
Y1415000D03*
X140500Y1458400D03*
X152100Y1423400D03*
X190800Y439500D03*
G54D92*
X24100Y690900D03*
X28900D03*
X74100Y576200D03*
X65635Y693906D03*
X70535D03*
X82000Y708200D03*
X72200Y711000D03*
X67200D03*
X70800Y981400D03*
X64200Y1004100D03*
X81398Y1137753D03*
X92300Y878454D03*
X87500D03*
X94000Y962800D03*
X103500Y979800D03*
X129900Y992500D03*
X140400Y572400D03*
X158535Y609679D03*
G54D12*
X29921Y24803D03*
Y111417D03*
Y458031D03*
Y544646D03*
Y717874D03*
Y804488D03*
X30000Y1164000D03*
X29921Y1250630D03*
Y1423858D03*
Y1510472D03*
Y1857086D03*
Y1943701D03*
G54D72*
X27471Y262553D03*
X19721D03*
X23596Y255053D03*
X24925Y305350D03*
X32675D03*
X28800Y312850D03*
X35375Y1649050D03*
X27625D03*
X31500Y1641550D03*
X27292Y1714868D03*
X19542D03*
X23417Y1707368D03*
X58692Y909868D03*
X50942D03*
X54817Y902368D03*
X78752Y1613297D03*
Y1619703D03*
X131525Y722550D03*
X135400Y730050D03*
X137752Y1613297D03*
Y1619703D03*
X109252Y1613297D03*
Y1619703D03*
X141625Y682250D03*
X149375D03*
X145500Y689750D03*
X139275Y722550D03*
X138694Y1422269D03*
X146444D03*
X148025Y1401454D03*
X155775D03*
X151900Y1408954D03*
X165494Y1437469D03*
X173244D03*
X169369Y1444969D03*
X142569Y1429769D03*
X165252Y1613297D03*
Y1619703D03*
G54D13*
X15906Y48110D03*
Y58110D03*
Y68110D03*
Y78110D03*
Y88110D03*
Y481339D03*
Y491339D03*
Y501339D03*
Y511339D03*
Y521339D03*
Y741181D03*
Y751181D03*
Y761181D03*
Y771181D03*
Y781181D03*
Y1187323D03*
Y1197323D03*
Y1207323D03*
Y1217323D03*
Y1227323D03*
Y1447165D03*
Y1457165D03*
Y1467165D03*
Y1477165D03*
Y1487165D03*
Y1880394D03*
Y1890394D03*
Y1900394D03*
Y1910394D03*
Y1920394D03*
X138937Y1778819D03*
X128937D03*
X118937D03*
X165000Y1370500D03*
Y1390500D03*
Y1380500D03*
G54D31*
X24100Y685300D03*
X28900D03*
X74100Y570600D03*
X82000Y702600D03*
X65635Y688306D03*
X70535D03*
X72200Y705400D03*
X67200D03*
X70800Y975800D03*
X64200Y998500D03*
X81398Y1132153D03*
X92300Y872854D03*
X87500D03*
X94000Y957200D03*
X103500Y974200D03*
X129900Y986900D03*
X140400Y566800D03*
X158535Y604079D03*
G54D40*
X83847Y61398D03*
X40000Y294300D03*
X56200Y252800D03*
X73500Y591000D03*
X76600Y986600D03*
X67600Y1025000D03*
X116900Y380100D03*
X91529Y533679D03*
X107100Y986000D03*
Y990800D03*
X94800Y1455500D03*
X106800Y1474500D03*
X165900Y532100D03*
X165700Y553300D03*
X182021Y613535D03*
X160300Y1462500D03*
G54D14*
X27559Y157480D03*
Y629921D03*
X17716Y1338583D03*
X27559Y1811023D03*
X179134Y78740D03*
X179133Y570866D03*
X179134Y1161417D03*
Y1889764D03*
G54D32*
X31868Y1089208D03*
Y1096958D03*
X24368Y1093083D03*
X112018Y566991D03*
Y574741D03*
X104518Y570866D03*
X112018Y1255968D03*
Y1263718D03*
X104518Y1259843D03*
G54D50*
X47498Y244499D03*
X52200Y244500D03*
X62700Y259800D03*
X45100Y582900D03*
X81500Y733200D03*
X63202Y1133947D03*
X103900Y482200D03*
X96300Y563300D03*
X129065Y678694D03*
X123465D03*
X124900Y728200D03*
X94500Y982300D03*
X130800Y981400D03*
X133500Y1476800D03*
X146700Y482300D03*
X163300Y702100D03*
X144300Y1116900D03*
X149002Y1116947D03*
G54D41*
X67998Y56503D03*
X67398Y71003D03*
X60600Y195000D03*
X61000Y240000D03*
X61600Y211300D03*
X54300Y263300D03*
X58300D03*
X37200Y256900D03*
X62600Y249200D03*
X73700Y543300D03*
X78600Y574500D03*
X73900Y558800D03*
X39000Y581300D03*
X77200Y705900D03*
X77000Y730800D03*
X43400Y896100D03*
X81398Y1126103D03*
X63498Y1123803D03*
X63198Y1142003D03*
X48300Y1755700D03*
X136779Y543071D03*
X116800Y588596D03*
X128900D03*
X91300Y573200D03*
X136679Y557171D03*
X129335Y662029D03*
X133535D03*
X104900Y662200D03*
X115600Y660200D03*
X116300Y670600D03*
X119600Y831800D03*
X111200D03*
X102900Y831796D03*
X121671Y939756D03*
X117300Y939700D03*
X110500D03*
X136000Y947800D03*
X131500D03*
X123300Y1001300D03*
X119300D03*
X114800D03*
X99000Y979700D03*
X135000Y1003200D03*
X123000Y1424200D03*
X127500D03*
X95500Y1464200D03*
X118000Y1424200D03*
X95600Y1423700D03*
X137000Y1501700D03*
X133000D03*
X129000D03*
X125000D03*
X121000D03*
X117000D03*
X113000D03*
X109000D03*
X93500Y1479200D03*
X145300Y582200D03*
X153500Y570000D03*
X151335Y635829D03*
X148435Y653329D03*
X144235D03*
X154500Y702700D03*
X167700Y699600D03*
X158500Y702700D03*
X149000Y949200D03*
X153000D03*
X157000D03*
X145000D03*
X140500Y947800D03*
X139100Y1003100D03*
X156631Y1431081D03*
X160831Y1430281D03*
X152331Y1431081D03*
X148500Y1474100D03*
X165400Y1430200D03*
X151000Y1491200D03*
X146500D03*
X142000D03*
X137900Y1491100D03*
G54D16*
X18600Y249100D03*
X27900Y269471D03*
X20010Y302982D03*
X11000Y578000D03*
X27300Y593000D03*
X27100Y578100D03*
X24500Y1102000D03*
X33000Y1575000D03*
X32900Y1656300D03*
X33000Y1718500D03*
X32949Y1709451D03*
X20056Y1774189D03*
X43900Y137200D03*
X36200Y318700D03*
X63200Y385100D03*
X62400Y430600D03*
X62900Y412900D03*
X61700Y421900D03*
X70900Y427200D03*
X66000Y510500D03*
X77400Y536300D03*
X83619Y581742D03*
X82900Y574500D03*
X70400Y565500D03*
X43337Y650145D03*
X49665Y642933D03*
X37000Y605000D03*
X86060Y695200D03*
X86000Y689900D03*
X57200Y667884D03*
X65000Y775000D03*
Y766000D03*
X43100Y866100D03*
X76500Y900500D03*
X65900Y900000D03*
X64100Y904800D03*
X85500Y1009500D03*
X73000Y966000D03*
X66900Y969100D03*
X60000Y966800D03*
X81500Y985900D03*
X51500Y974100D03*
X37200Y1091700D03*
X52100Y1132700D03*
X71000Y1232600D03*
X59500Y1627500D03*
X64400Y1605900D03*
X53300Y1609200D03*
X62300Y1641300D03*
X61500Y1716500D03*
X72500Y1717000D03*
Y1699000D03*
X86500Y1713610D03*
Y1700110D03*
Y1726000D03*
X79000Y1766500D03*
X71500Y1760000D03*
X72500Y1733000D03*
X87000Y1774110D03*
X81000Y1802000D03*
X73000Y1813000D03*
X72500Y1830000D03*
X72000Y1798000D03*
X86500Y1793110D03*
X57000Y1805500D03*
X84000Y1869600D03*
X75500Y1838500D03*
X73000Y1847000D03*
X85100Y1844500D03*
X85700Y1852300D03*
X82000Y1915000D03*
X66000Y1917000D03*
X118500Y442000D03*
X122500Y429000D03*
X125100Y408900D03*
X115000Y486100D03*
X106500Y469500D03*
X115500Y476700D03*
X96900Y541600D03*
X99800Y545600D03*
X120800Y598700D03*
X112018Y584900D03*
X106338Y580496D03*
X118565Y592846D03*
X94545Y601197D03*
X101800Y557400D03*
X135200Y566400D03*
X96500Y567600D03*
X99578Y605771D03*
X93063Y629134D03*
X91463Y623143D03*
X129000Y653600D03*
X122088Y665912D03*
X119300Y656600D03*
X111400Y658500D03*
X125202Y657500D03*
X105500Y732000D03*
X95500Y728000D03*
X117500Y724500D03*
X109000Y809500D03*
X119300Y837000D03*
X92700Y858100D03*
X92400Y848900D03*
X103400Y838300D03*
X98700Y877100D03*
X92800Y865300D03*
X111100Y876700D03*
X108200Y953500D03*
X112984Y946835D03*
X120054Y945600D03*
X130903Y958178D03*
X133500Y953000D03*
X94500Y950500D03*
X110400Y997850D03*
X119080Y992900D03*
X127700Y998400D03*
X87600Y965900D03*
X90542Y987958D03*
X97958Y966958D03*
X103500Y966500D03*
X130900Y1003400D03*
X91500Y1030500D03*
X128500Y1076800D03*
X122862Y1385500D03*
X129000Y1416425D03*
X99500Y1407500D03*
X100000Y1443000D03*
X111833Y1469667D03*
X101000Y1460750D03*
X113024Y1452079D03*
X117122Y1448001D03*
X117195Y1456070D03*
X121338Y1452021D03*
X117024Y1452000D03*
X136100Y1463900D03*
X100200Y1433800D03*
X134400Y1454300D03*
X99700Y1450700D03*
X133000Y1447600D03*
X103000Y1429500D03*
X123000Y1431300D03*
X126975Y1435400D03*
X127300Y1468800D03*
X117500Y1519500D03*
X104333Y1498167D03*
X130180Y1486680D03*
X136500Y1481425D03*
X98000Y1564700D03*
X120500Y1606000D03*
X89500Y1610000D03*
X136500Y1651000D03*
X108500Y1727000D03*
X98500Y1717000D03*
Y1696500D03*
X99000Y1707000D03*
X109500Y1719500D03*
X110000Y1709500D03*
X109500Y1699000D03*
X119500Y1710110D03*
Y1696610D03*
Y1725110D03*
X111500Y1768500D03*
X117500Y1732000D03*
X119500Y1760000D03*
X97500Y1775500D03*
X108268Y1777300D03*
X119500Y1747110D03*
X138000Y1824000D03*
X110500Y1801000D03*
X88500Y1785000D03*
X97500Y1796000D03*
X98000Y1786000D03*
X107768Y1789110D03*
X120000Y1811500D03*
X119500Y1796500D03*
X137000Y1877500D03*
X114000Y1843500D03*
X97000Y1850500D03*
X120500Y1836500D03*
Y1850500D03*
X108500Y1851610D03*
X162612Y438169D03*
X143400Y408200D03*
X144400Y470800D03*
X149000Y522500D03*
X174800Y532200D03*
X151500Y533000D03*
X164200Y541900D03*
X149500Y574600D03*
X145230Y571700D03*
X163100Y604717D03*
X174100Y652900D03*
X176300Y608635D03*
X157200Y620800D03*
X146663Y634051D03*
X148595Y618300D03*
X151335Y640400D03*
X145200Y644600D03*
X153200Y653200D03*
X179017Y620013D03*
X173000Y691000D03*
X142000Y701000D03*
X158500Y695000D03*
X145500Y675000D03*
X167600Y703300D03*
X145000Y711750D03*
X160500Y916500D03*
X139500Y951500D03*
X143100Y1007100D03*
X162000Y1027000D03*
X186000Y1133000D03*
X178500Y1268500D03*
X159774Y1414374D03*
X165500Y1450600D03*
X138000Y1448500D03*
X142400Y1499900D03*
X148500Y1479500D03*
X139000Y1696500D03*
Y1712500D03*
X138500Y1727500D03*
X181500Y1716500D03*
X158500D03*
X167500Y1716000D03*
X182000Y1726000D03*
Y1704000D03*
X168500Y1705000D03*
X158500D03*
X184500Y1696500D03*
X163000Y1697000D03*
X174268Y1697110D03*
X152000D03*
Y1710610D03*
Y1725610D03*
X185000Y1738500D03*
X183600Y1765100D03*
X169000Y1781500D03*
X162500Y1773000D03*
X152500Y1771110D03*
X173268Y1776000D03*
X139000Y1800500D03*
X156500Y1782000D03*
X155500Y1798500D03*
X166500Y1798000D03*
X179000Y1798500D03*
X185500Y1804500D03*
X186000Y1790000D03*
X162000D03*
X172768Y1790110D03*
X152000D03*
X139000Y1851000D03*
X138500Y1839500D03*
X185000Y1852500D03*
X161500D03*
X183100Y1838300D03*
X173000Y1852610D03*
X151500Y1851110D03*
X139861Y1889461D03*
X189928Y435800D03*
X197500Y481500D03*
X189000Y1432000D03*
G54D90*
X32500Y321300D03*
X33500Y1083600D03*
X22000Y1644300D03*
X21800Y1720700D03*
X23600Y1692800D03*
X60300Y155300D03*
Y163300D03*
Y179300D03*
Y159300D03*
Y175300D03*
X49900Y213400D03*
X61200Y217000D03*
X60300Y199300D03*
X36200Y272300D03*
X74200Y431300D03*
X64400Y577200D03*
X81956Y690465D03*
X84100Y686400D03*
X48800Y916400D03*
X72100Y999800D03*
X52800Y1769800D03*
X91703Y61502D03*
X89200Y71500D03*
X121300Y437500D03*
X129356Y692165D03*
X129256Y688065D03*
Y683665D03*
X116300Y670600D03*
X87396Y848500D03*
Y844100D03*
Y852900D03*
X87400Y857200D03*
Y865700D03*
Y861500D03*
X115300Y1408200D03*
X94700Y1451000D03*
X113100Y1425900D03*
X94700Y1439000D03*
X87700Y1484000D03*
X132200Y1482000D03*
X163300Y545600D03*
X166100Y622700D03*
X155729Y615065D03*
X175200Y701100D03*
X155496Y1419200D03*
Y1415000D03*
X143900Y1458400D03*
X155500Y1423400D03*
X194200Y439500D03*
G54D60*
X77400Y980050D03*
Y976300D03*
Y972550D03*
X88000D03*
Y976300D03*
Y980050D03*
G54D42*
X67998Y53103D03*
X67398Y67603D03*
X60600Y191600D03*
X62600Y245800D03*
X61000Y236600D03*
X61600Y207900D03*
X54300Y259900D03*
X58300D03*
X37200Y253500D03*
X73700Y539900D03*
X78600Y571100D03*
X73900Y555400D03*
X39000Y577900D03*
X77200Y702500D03*
X77000Y727400D03*
X43400Y892700D03*
X81398Y1122703D03*
X63498Y1120403D03*
X63198Y1138603D03*
X48300Y1752300D03*
X136779Y539671D03*
X116800Y585196D03*
X128900D03*
X91300Y569800D03*
X136679Y553771D03*
X129335Y658629D03*
X133535D03*
X104900Y658800D03*
X115600Y656800D03*
X116300Y667200D03*
X119600Y828400D03*
X111200D03*
X102900Y828396D03*
X121671Y936356D03*
X117300Y936300D03*
X110500D03*
X136000Y944400D03*
X131500D03*
X123300Y997900D03*
X119300D03*
X114800D03*
X99000Y976300D03*
X135000Y999800D03*
X123000Y1420800D03*
X127500D03*
X118000D03*
X95600Y1420300D03*
X95500Y1460800D03*
X137000Y1498300D03*
X133000D03*
X129000D03*
X125000D03*
X121000D03*
X117000D03*
X113000D03*
X109000D03*
X93500Y1475800D03*
X145300Y578800D03*
X153500Y566600D03*
X151335Y632429D03*
X148435Y649929D03*
X144235D03*
X154500Y699300D03*
X167700Y696200D03*
X158500Y699300D03*
X149000Y945800D03*
X153000D03*
X157000D03*
X145000D03*
X140500Y944400D03*
X139100Y999700D03*
X156631Y1427681D03*
X160831Y1426881D03*
X152331Y1427681D03*
X148500Y1470700D03*
X165400Y1426800D03*
X151000Y1487800D03*
X146500D03*
X142000D03*
X137900Y1487700D03*
G54D51*
X69635Y361900D03*
X110735Y361800D03*
X140465D03*
X99365Y361900D03*
X187565Y1507700D03*
X157835D03*
G54D15*
X31299Y230866D03*
Y220866D03*
Y210866D03*
Y348563D03*
Y338563D03*
Y358563D03*
Y903917D03*
Y923917D03*
Y913917D03*
Y1064587D03*
Y1054587D03*
Y1044587D03*
Y1619941D03*
Y1609941D03*
Y1629941D03*
Y1757638D03*
Y1747638D03*
Y1737638D03*
G54D33*
X32359Y1680500D03*
X60641D03*
G54D65*
X22900Y397800D03*
Y418300D03*
X19100Y667000D03*
X36600Y1551500D03*
X81100Y398500D03*
X47700Y397800D03*
X81100Y419000D03*
X47700Y418300D03*
X43900Y667000D03*
X73600Y798400D03*
X63700Y1090600D03*
X88500D03*
X61400Y1551500D03*
X137900Y88500D03*
X113100D03*
X105900Y398500D03*
Y419000D03*
X98400Y798400D03*
X185300Y397900D03*
X160500D03*
X185200Y356700D03*
X160400D03*
X185400Y376900D03*
X160600D03*
X185300Y418400D03*
X160500D03*
X184900Y1531500D03*
X160100D03*
X185000Y1551600D03*
X160200D03*
G54D59*
X89435Y642629D03*
Y635029D03*
X89500Y1461700D03*
Y1469300D03*
X172100Y549100D03*
Y541500D03*
X152265Y601371D03*
X170100Y607600D03*
Y615200D03*
X152265Y608971D03*
X167000Y1457700D03*
Y1465300D03*
G54D61*
X70202Y1138347D03*
Y1125047D03*
X41600Y1767550D03*
Y1754250D03*
X88502Y1136247D03*
Y1122947D03*
G54D38*
X21350Y1781000D03*
X34650D03*
X77953Y54502D03*
X71650Y584000D03*
X58350D03*
X45050Y593000D03*
X58350D03*
X81850Y715400D03*
X81350Y740400D03*
X60150Y1011800D03*
X73450D03*
X64450Y1032100D03*
X77750D03*
X91253Y54502D03*
X95850Y68500D03*
X109150D03*
X95150Y715400D03*
X94650Y740400D03*
G54D34*
X27900Y246900D03*
X25300Y328500D03*
X36300D03*
X16200Y1657100D03*
X27200D03*
X15800Y1699200D03*
X26800D03*
X38900Y246900D03*
X124696Y1392300D03*
X135696D03*
X106000Y1387500D03*
X117000D03*
X154000D03*
X143000D03*
G54D52*
X69000Y440000D03*
X74000D03*
X79000D03*
X84000D03*
X60400Y1575600D03*
X65400D03*
X70400D03*
X75400D03*
X96500Y439500D03*
X101500D03*
X106500D03*
X111500D03*
X128500Y1575500D03*
X133500D03*
X93500D03*
X98500D03*
X103500D03*
X108500D03*
X141000Y439500D03*
X146000D03*
X151000D03*
X156000D03*
X169000D03*
X174000D03*
X179000D03*
X184000D03*
X162500Y1575500D03*
X167500D03*
X172500D03*
X177500D03*
X138500D03*
X143500D03*
G54D43*
X71802Y56547D03*
X71400Y71754D03*
X75200Y741500D03*
X75700Y719100D03*
X53800Y1013100D03*
X103500Y597500D03*
X146365Y611321D03*
G54D93*
X34400Y294300D03*
X78247Y61398D03*
X50600Y252800D03*
X85929Y533679D03*
X67900Y591000D03*
X71000Y986600D03*
X62000Y1025000D03*
X111300Y380100D03*
X101500Y986000D03*
Y990800D03*
X89200Y1455500D03*
X101200Y1474500D03*
X160300Y532100D03*
X160100Y553300D03*
X176421Y613535D03*
X154700Y1462500D03*
G54D62*
X80200Y1477500D03*
X107600Y558300D03*
X115200D03*
X87800Y1477500D03*
X106770Y1480640D03*
X99170D03*
X183700Y1606500D03*
X180700Y1641000D03*
X188300D03*
X191300Y1606500D03*
G54D80*
X150000Y64500D03*
X152500Y1906000D03*
G54D37*
X93206Y677415D03*
Y682415D03*
Y687415D03*
Y692415D03*
X113306D03*
Y687415D03*
Y682415D03*
Y677415D03*
G54D53*
X72000Y473548D03*
Y491452D03*
X90000Y473548D03*
Y491452D03*
X176000Y473048D03*
Y490952D03*
X158000Y473048D03*
Y490952D03*
G54D29*
X33400Y570800D03*
X27700Y1106000D03*
X22000Y1640200D03*
X34100Y1774400D03*
X23300Y1769600D03*
X70700Y63500D03*
X60300Y171300D03*
Y183300D03*
Y167300D03*
Y187300D03*
X61200Y221000D03*
X49900Y217400D03*
X36082Y264217D03*
X60300Y280000D03*
X81944Y694635D03*
X83400Y682200D03*
X68700Y730000D03*
X72100Y1004300D03*
X63000Y1020600D03*
X75700Y1025400D03*
X75800Y1020900D03*
X41400Y1096000D03*
X72200Y1175100D03*
X38400Y1788200D03*
X102100Y549600D03*
X87100Y569900D03*
X94700Y671000D03*
X119000Y660200D03*
X108300Y662200D03*
X91200Y707900D03*
X89700Y733400D03*
X113100Y1421600D03*
X107500Y1408100D03*
X133200Y1428300D03*
X94700Y1446500D03*
X153500Y430800D03*
X148700Y568000D03*
X156200Y587000D03*
X166100Y626700D03*
X177700Y624300D03*
X151404Y1394000D03*
X143900Y1466400D03*
Y1462400D03*
X143600Y1453300D03*
X160700Y1458000D03*
G54D35*
X33600Y1769900D03*
X81300Y71500D03*
X63800Y662300D03*
Y657600D03*
X54300Y1764700D03*
X115800Y769100D03*
Y764100D03*
X105300Y1058400D03*
Y1053700D03*
X187900Y1652700D03*
Y1648000D03*
X147447Y1878698D03*
X147400Y1883700D03*
G54D44*
X71802Y52947D03*
X71400Y68154D03*
X75200Y737900D03*
X75700Y715500D03*
X53800Y1009500D03*
X103500Y593900D03*
X146365Y607721D03*
G54D96*
X35000Y581300D03*
X58100Y1030800D03*
X87400Y574100D03*
X149500Y578600D03*
X164600Y608500D03*
X150500Y699200D03*
G54D86*
X78900Y1498700D03*
Y1523500D03*
X124298Y1883503D03*
Y1908303D03*
X145798Y1151303D03*
Y1126503D03*
G54D81*
X171370Y634819D03*
X159800D03*
X171370Y645839D03*
X159800D03*
G54D45*
X47244Y68110D03*
Y501338D03*
Y761181D03*
Y1207323D03*
Y1467165D03*
Y1900393D03*
G54D30*
X134709Y710500D03*
X117291D03*
G54D54*
X85400Y544750D03*
X83430D03*
X81465D03*
Y561050D03*
X83430D03*
X85400D03*
X89335Y544750D03*
X87370D03*
Y561050D03*
X89335D03*
X108710Y612629D03*
X110675D03*
X112645D03*
X114615D03*
X116580D03*
X118550D03*
X120520D03*
X122490D03*
X124455D03*
X126425D03*
X128395D03*
X130360D03*
Y646029D03*
X128395D03*
X126425D03*
X124455D03*
X122490D03*
X120520D03*
X118550D03*
X116580D03*
X114615D03*
X112645D03*
X110675D03*
X108710D03*
X153135Y542950D03*
X151170D03*
X149200D03*
X147230D03*
X145265D03*
Y559250D03*
X147230D03*
X149200D03*
X151170D03*
X153135D03*
G54D36*
X28000Y1769900D03*
X75700Y71500D03*
X58200Y662300D03*
Y657600D03*
X48700Y1764700D03*
X110200Y769100D03*
Y764100D03*
X99700Y1058400D03*
Y1053700D03*
X182300Y1652700D03*
Y1648000D03*
X141847Y1878698D03*
X141800Y1883700D03*
G54D28*
X32682Y264217D03*
X30000Y570800D03*
X24300Y1106000D03*
X18600Y1640200D03*
X30700Y1774400D03*
X19900Y1769600D03*
X35000Y1788200D03*
X67300Y63500D03*
X56900Y171300D03*
Y183300D03*
Y167300D03*
Y187300D03*
X57800Y221000D03*
X46500Y217400D03*
X56900Y280000D03*
X83700Y569900D03*
X78544Y694635D03*
X80000Y682200D03*
X86300Y733400D03*
X65300Y730000D03*
X68700Y1004300D03*
X59600Y1020600D03*
X72300Y1025400D03*
X72400Y1020900D03*
X38000Y1096000D03*
X68800Y1175100D03*
X98700Y549600D03*
X91300Y671000D03*
X115600Y660200D03*
X104900Y662200D03*
X87800Y707900D03*
X109700Y1421600D03*
X104100Y1408100D03*
X129800Y1428300D03*
X91300Y1446500D03*
X150100Y430800D03*
X145300Y568000D03*
X152800Y587000D03*
X162700Y626700D03*
X174300Y624300D03*
X148004Y1394000D03*
X140500Y1466400D03*
Y1462400D03*
X140200Y1453300D03*
X157300Y1458000D03*
G54D95*
X30300Y1787800D03*
X64500Y573000D03*
X81900Y966200D03*
X71200Y1144500D03*
X87000Y1143000D03*
X94800Y1431500D03*
Y1434900D03*
X133300Y1432000D03*
X94800Y1442800D03*
X163400Y549300D03*
X144300Y695500D03*
G54D91*
X32700Y253500D03*
X19283Y307282D03*
X32900Y1660800D03*
X25900Y1721700D03*
X56600Y191600D03*
X57400Y207900D03*
X56900Y236600D03*
X63000Y264300D03*
X39200Y343800D03*
X81400Y530500D03*
X78400Y587600D03*
X49600Y573500D03*
X61400Y673400D03*
X57400D03*
X64100Y909400D03*
X77002Y1134497D03*
X83500Y1461800D03*
X96100Y530500D03*
X124900Y585204D03*
X120800D03*
X93065Y594071D03*
X97265D03*
X92465Y606971D03*
X95200Y662300D03*
X110900Y881400D03*
X102600D03*
X119300D03*
X122529Y952344D03*
X117529D03*
X112529D03*
X100500Y1420300D03*
X91500D03*
X105000D03*
X135000Y1408404D03*
X134700Y1400604D03*
X107500Y1486800D03*
X170600Y529100D03*
X155600Y529000D03*
X158000Y575200D03*
X170200Y623700D03*
X180365Y642371D03*
X137765Y658671D03*
X154500Y683800D03*
X149500Y708300D03*
X147900Y999700D03*
X152100Y999800D03*
X163500Y994300D03*
X159500D03*
X143800Y999800D03*
X137500Y1440300D03*
G54D89*
X35000Y584900D03*
X58100Y1034400D03*
X87400Y577700D03*
X149500Y582200D03*
X164600Y612100D03*
X150500Y702800D03*
G54D64*
X71250Y1613297D03*
Y1619703D03*
X130250Y1613297D03*
Y1619703D03*
X101750Y1613297D03*
Y1619703D03*
X157750Y1613297D03*
Y1619703D03*
G54D46*
X80709Y119409D03*
Y329409D03*
X149606Y119409D03*
Y329409D03*
G54D73*
X116175Y846304D03*
X113620D03*
X111060D03*
X108500D03*
X105940D03*
X103380D03*
X100825D03*
Y868504D03*
X103380D03*
X105940D03*
X108500D03*
X111060D03*
X113620D03*
X116175D03*
X121640Y963000D03*
X119080D03*
X116520D03*
X113960D03*
Y985200D03*
X116520D03*
X119080D03*
X121640D03*
X155825Y732304D03*
X158380D03*
X160940D03*
X163500D03*
X166060D03*
X168620D03*
X171175D03*
Y710104D03*
X168620D03*
X166060D03*
X163500D03*
X160940D03*
X158380D03*
X155825D03*
X137340Y959500D03*
X139900D03*
X142460D03*
X145020D03*
X147580D03*
X150140D03*
X152700D03*
X155260D03*
Y981700D03*
X152700D03*
X150140D03*
X147580D03*
X145020D03*
X142460D03*
X139900D03*
X137340D03*
G54D82*
X180465Y631371D03*
Y634971D03*
G54D55*
X73900Y550100D03*
X136771Y548521D03*
X132735Y593429D03*
X125835Y593629D03*
X131935Y601929D03*
X105000Y603200D03*
X101900Y654100D03*
X92971Y617335D03*
X117100Y1430100D03*
X144329Y598765D03*
X139929Y604165D03*
X140135Y593229D03*
X160700Y615900D03*
X151029Y627565D03*
X156700Y626800D03*
X179000Y706500D03*
X147600Y994600D03*
X154000Y994500D03*
X142000D03*
G54D94*
X96457Y1773425D03*
G54D88*
X26700Y1787800D03*
X60900Y573000D03*
X78300Y966200D03*
X83400Y1143000D03*
X67600Y1144500D03*
X91200Y1431500D03*
Y1434900D03*
X129700Y1432000D03*
X91200Y1442800D03*
X159800Y549300D03*
X140700Y695500D03*
G54D57*
X36250Y690560D03*
Y688000D03*
Y685440D03*
X51750Y690560D03*
Y688000D03*
Y685440D03*
X58250D03*
Y690560D03*
X42750Y685440D03*
Y690560D03*
G54D83*
X141100Y1401696D03*
Y1410096D03*
X158600Y1446404D03*
Y1438004D03*
G54D74*
X113800Y1397140D03*
Y1399700D03*
Y1402260D03*
X106400D03*
Y1399700D03*
Y1397140D03*
G54D47*
X80709Y139409D03*
Y309409D03*
X149606Y139409D03*
Y309409D03*
G54D56*
X73403Y606702D03*
Y633502D03*
X122097Y1125298D03*
Y1152098D03*
X98497Y1883198D03*
Y1909998D03*
G54D84*
X147500Y1437250D03*
X143625Y1444750D03*
X151375D03*
G54D63*
X66875Y674606D03*
X69435D03*
X71995D03*
Y681106D03*
X66875D03*
G54D66*
X48200Y1760300D03*
X98600Y553300D03*
X86800Y537800D03*
X96100D03*
X112900Y603500D03*
X107600Y593700D03*
X170600Y536400D03*
X160900Y536500D03*
G54D75*
X125000Y1409454D03*
X121125Y1401954D03*
X128875D03*
G54D39*
X72200Y86200D03*
X72602Y757897D03*
X63700Y1050100D03*
X99000Y86200D03*
X99402Y757897D03*
X90500Y1050100D03*
G54D48*
X80709Y161889D03*
Y171889D03*
Y181889D03*
Y191889D03*
Y204409D03*
Y214409D03*
Y224409D03*
Y234409D03*
Y244409D03*
Y256929D03*
Y266929D03*
Y276929D03*
Y286929D03*
X110709Y161889D03*
Y171889D03*
X100709Y161889D03*
Y171889D03*
X90709Y161889D03*
Y171889D03*
X110709Y181889D03*
Y191889D03*
X100709Y181889D03*
Y191889D03*
X90709Y181889D03*
Y191889D03*
X110709Y204409D03*
Y214409D03*
Y224409D03*
Y234409D03*
Y244409D03*
X100709Y204409D03*
Y214409D03*
Y224409D03*
Y234409D03*
Y244409D03*
X90709Y204409D03*
Y214409D03*
Y224409D03*
Y234409D03*
Y244409D03*
X110709Y256929D03*
Y266929D03*
X100709Y256929D03*
Y266929D03*
X90709Y256929D03*
Y266929D03*
X110709Y276929D03*
Y286929D03*
X100709Y276929D03*
Y286929D03*
X90709Y276929D03*
Y286929D03*
X179606Y161889D03*
Y171889D03*
X169606Y161889D03*
Y171889D03*
X159606Y161889D03*
Y171889D03*
X149606Y161889D03*
Y171889D03*
X179606Y181889D03*
Y191889D03*
X169606Y181889D03*
Y191889D03*
X159606Y181889D03*
Y191889D03*
X149606Y181889D03*
Y191889D03*
X179606Y204409D03*
Y214409D03*
Y224409D03*
Y234409D03*
Y244409D03*
X169606Y204409D03*
Y214409D03*
Y224409D03*
Y234409D03*
Y244409D03*
X159606Y204409D03*
Y214409D03*
Y224409D03*
Y234409D03*
Y244409D03*
X149606Y204409D03*
Y214409D03*
Y224409D03*
Y234409D03*
Y244409D03*
X179606Y256929D03*
Y266929D03*
X169606Y256929D03*
Y266929D03*
X159606Y256929D03*
Y266929D03*
X149606Y256929D03*
Y266929D03*
X179606Y276929D03*
Y286929D03*
X169606Y276929D03*
Y286929D03*
X159606Y276929D03*
Y286929D03*
X149606Y276929D03*
Y286929D03*
G54D58*
X49900Y883800D03*
Y894800D03*
X63800Y986600D03*
Y975600D03*
X39000Y1022500D03*
Y1033500D03*
X96000Y931000D03*
Y942000D03*
X147000Y732000D03*
Y721000D03*
G54D76*
X111882Y1461600D03*
X114441D03*
X117000D03*
X119559D03*
X122118D03*
Y1442400D03*
X119559D03*
X117000D03*
X114441D03*
X111882D03*
G54D85*
X142300Y1471800D03*
Y1480800D03*
G54D49*
X47498Y238899D03*
X52200Y238900D03*
X62700Y254200D03*
X45100Y577300D03*
X81500Y727600D03*
X63202Y1128347D03*
X103900Y476600D03*
X96300Y557700D03*
X129065Y673094D03*
X123465D03*
X124900Y722600D03*
X94500Y976700D03*
X130800Y975800D03*
X133500Y1471200D03*
X146700Y476700D03*
X163300Y696500D03*
X144300Y1111300D03*
X149002Y1111347D03*
G54D67*
X51800Y1760300D03*
X102200Y553300D03*
X90400Y537800D03*
X99700D03*
X116500Y603500D03*
X111200Y593700D03*
X174200Y536400D03*
X164500Y536500D03*
G54D87*
X86699Y949600D03*
X63901D03*
G54D68*
X96457Y1747835D03*
Y1823031D03*
X178937Y1328740D03*
X161417Y1747835D03*
Y1823031D03*
G54D77*
X126600Y1457118D03*
Y1454559D03*
Y1452000D03*
Y1449441D03*
Y1446882D03*
X107400D03*
Y1449441D03*
Y1452000D03*
Y1454559D03*
Y1457118D03*
G54D78*
X117000Y1452000D03*
G54D69*
X136235Y618504D03*
Y620469D03*
Y622439D03*
Y624409D03*
Y626374D03*
Y628344D03*
Y630314D03*
Y632284D03*
Y634249D03*
Y636219D03*
Y638189D03*
Y640154D03*
X102835D03*
Y638189D03*
Y636219D03*
Y634249D03*
Y632284D03*
Y630314D03*
Y628344D03*
Y626374D03*
Y624409D03*
Y622439D03*
Y620469D03*
Y618504D03*
G54D79*
X161417Y1773425D03*
G54D98*
X461833Y256900D03*
X448416Y310682D03*
X462033Y1664200D03*
X455033Y1725100D03*
X485733Y195000D03*
X486533Y211300D03*
X486033Y240000D03*
X492133Y267700D03*
X468333Y347200D03*
X510533Y533900D03*
X507533Y591000D03*
X478733Y576900D03*
X490533Y676800D03*
X486533D03*
X493233Y912800D03*
X506135Y1137897D03*
X512633Y1465200D03*
X525233Y533900D03*
X554033Y588604D03*
X549933D03*
X522198Y597471D03*
X526398D03*
X521598Y610371D03*
X524333Y665700D03*
X540033Y884800D03*
X531733D03*
X548433D03*
X551662Y955744D03*
X546662D03*
X541662D03*
X564133Y1411804D03*
X563833Y1404004D03*
X529633Y1423700D03*
X520633D03*
X534133D03*
X536633Y1490200D03*
X599733Y532500D03*
X584733Y532400D03*
X587133Y578600D03*
X599333Y627100D03*
X609498Y645771D03*
X566898Y662071D03*
X583633Y687200D03*
X578633Y711700D03*
X577033Y1003100D03*
X581233Y1003200D03*
X592633Y997700D03*
X588633D03*
X572933Y1003200D03*
X566633Y1443700D03*
G54D97*
X461933Y272300D03*
X458233Y321300D03*
X459233Y1083600D03*
X447733Y1644300D03*
X447533Y1720700D03*
X449333Y1692800D03*
X514933Y71500D03*
X486033Y155300D03*
Y163300D03*
Y179300D03*
Y159300D03*
Y175300D03*
X475633Y213400D03*
X486933Y217000D03*
X486033Y199300D03*
X499933Y431300D03*
X490133Y577200D03*
X507689Y690465D03*
X509833Y686400D03*
X513129Y848500D03*
Y844100D03*
Y852900D03*
X513133Y857200D03*
Y865700D03*
Y861500D03*
X474533Y916400D03*
X497833Y999800D03*
X513433Y1484000D03*
X478533Y1769800D03*
X517436Y61502D03*
X547033Y437500D03*
X555089Y692165D03*
X554989Y688065D03*
Y683665D03*
X542033Y670600D03*
X541033Y1408200D03*
X520433Y1451000D03*
X538833Y1425900D03*
X520433Y1439000D03*
X557933Y1482000D03*
X589033Y545600D03*
X591833Y622700D03*
X581462Y615065D03*
X600933Y701100D03*
X581229Y1419200D03*
Y1415000D03*
X569633Y1458400D03*
X581233Y1423400D03*
X619933Y439500D03*
G54D92*
X453233Y690900D03*
X458033D03*
X503233Y576200D03*
X494768Y693906D03*
X499668D03*
X511133Y708200D03*
X501333Y711000D03*
X496333D03*
X499933Y981400D03*
X493333Y1004100D03*
X510531Y1137753D03*
X521433Y878454D03*
X516633D03*
X523133Y962800D03*
X532633Y979800D03*
X559033Y992500D03*
X569533Y572400D03*
X587668Y609679D03*
G54D12*
X459054Y24803D03*
Y111417D03*
Y458031D03*
Y544646D03*
Y717874D03*
Y804488D03*
X459133Y1164000D03*
X459054Y1250630D03*
Y1423858D03*
Y1510472D03*
Y1857086D03*
Y1943701D03*
G54D72*
X456604Y262553D03*
X448854D03*
X452729Y255053D03*
X454058Y305350D03*
X461808D03*
X457933Y312850D03*
X464508Y1649050D03*
X456758D03*
X460633Y1641550D03*
X456425Y1714868D03*
X448675D03*
X452550Y1707368D03*
X487825Y909868D03*
X480075D03*
X483950Y902368D03*
X507885Y1613297D03*
Y1619703D03*
X560658Y722550D03*
X564533Y730050D03*
X566885Y1613297D03*
Y1619703D03*
X538385Y1613297D03*
Y1619703D03*
X570758Y682250D03*
X578508D03*
X574633Y689750D03*
X568408Y722550D03*
X567827Y1422269D03*
X575577D03*
X577158Y1401454D03*
X584908D03*
X581033Y1408954D03*
X594627Y1437469D03*
X602377D03*
X598502Y1444969D03*
X571702Y1429769D03*
X594385Y1613297D03*
Y1619703D03*
G54D13*
X445039Y48110D03*
Y58110D03*
Y68110D03*
Y78110D03*
Y88110D03*
Y481339D03*
Y491339D03*
Y501339D03*
Y511339D03*
Y521339D03*
Y741181D03*
Y751181D03*
Y761181D03*
Y771181D03*
Y781181D03*
Y1187323D03*
Y1197323D03*
Y1207323D03*
Y1217323D03*
Y1227323D03*
Y1447165D03*
Y1457165D03*
Y1467165D03*
Y1477165D03*
Y1487165D03*
Y1880394D03*
Y1890394D03*
Y1900394D03*
Y1910394D03*
Y1920394D03*
X568070Y1778819D03*
X558070D03*
X548070D03*
X594133Y1370500D03*
Y1390500D03*
Y1380500D03*
G54D31*
X453233Y685300D03*
X458033D03*
X503233Y570600D03*
X511133Y702600D03*
X494768Y688306D03*
X499668D03*
X501333Y705400D03*
X496333D03*
X499933Y975800D03*
X493333Y998500D03*
X510531Y1132153D03*
X521433Y872854D03*
X516633D03*
X523133Y957200D03*
X532633Y974200D03*
X559033Y986900D03*
X569533Y566800D03*
X587668Y604079D03*
G54D40*
X512980Y61398D03*
X469133Y294300D03*
X485333Y252800D03*
X502633Y591000D03*
X505733Y986600D03*
X496733Y1025000D03*
X546033Y380100D03*
X520662Y533679D03*
X536233Y986000D03*
Y990800D03*
X523933Y1455500D03*
X535933Y1474500D03*
X595033Y532100D03*
X594833Y553300D03*
X611154Y613535D03*
X589433Y1462500D03*
G54D14*
X456692Y157480D03*
Y629921D03*
X446849Y1338583D03*
X456692Y1811023D03*
X608267Y78740D03*
X608266Y570866D03*
X608267Y1161417D03*
Y1889764D03*
G54D32*
X461001Y1089208D03*
Y1096958D03*
X453501Y1093083D03*
X541151Y566991D03*
Y574741D03*
X533651Y570866D03*
X541151Y1255968D03*
Y1263718D03*
X533651Y1259843D03*
G54D50*
X476631Y244499D03*
X481333Y244500D03*
X491833Y259800D03*
X474233Y582900D03*
X510633Y733200D03*
X492335Y1133947D03*
X533033Y482200D03*
X525433Y563300D03*
X558198Y678694D03*
X552598D03*
X554033Y728200D03*
X523633Y982300D03*
X559933Y981400D03*
X562633Y1476800D03*
X575833Y482300D03*
X592433Y702100D03*
X573433Y1116900D03*
X578135Y1116947D03*
G54D41*
X497131Y56503D03*
X496531Y71003D03*
X489733Y195000D03*
X490133Y240000D03*
X490733Y211300D03*
X483433Y263300D03*
X487433D03*
X466333Y256900D03*
X491733Y249200D03*
X502833Y543300D03*
X507733Y574500D03*
X503033Y558800D03*
X468133Y581300D03*
X506333Y705900D03*
X506133Y730800D03*
X472533Y896100D03*
X510531Y1126103D03*
X492631Y1123803D03*
X492331Y1142003D03*
X477433Y1755700D03*
X565912Y543071D03*
X545933Y588596D03*
X558033D03*
X520433Y573200D03*
X565812Y557171D03*
X558468Y662029D03*
X562668D03*
X534033Y662200D03*
X544733Y660200D03*
X545433Y670600D03*
X548733Y831800D03*
X540333D03*
X532033Y831796D03*
X550804Y939756D03*
X546433Y939700D03*
X539633D03*
X565133Y947800D03*
X560633D03*
X552433Y1001300D03*
X548433D03*
X543933D03*
X528133Y979700D03*
X564133Y1003200D03*
X552133Y1424200D03*
X556633D03*
X524633Y1464200D03*
X547133Y1424200D03*
X524733Y1423700D03*
X566133Y1501700D03*
X562133D03*
X558133D03*
X554133D03*
X550133D03*
X546133D03*
X542133D03*
X538133D03*
X522633Y1479200D03*
X574433Y582200D03*
X582633Y570000D03*
X580468Y635829D03*
X577568Y653329D03*
X573368D03*
X583633Y702700D03*
X596833Y699600D03*
X587633Y702700D03*
X578133Y949200D03*
X582133D03*
X586133D03*
X574133D03*
X569633Y947800D03*
X568233Y1003100D03*
X585764Y1431081D03*
X589964Y1430281D03*
X581464Y1431081D03*
X577633Y1474100D03*
X594533Y1430200D03*
X580133Y1491200D03*
X575633D03*
X571133D03*
X567033Y1491100D03*
G54D16*
X447733Y249100D03*
X457033Y269471D03*
X449143Y302982D03*
X440133Y578000D03*
X456433Y593000D03*
X456233Y578100D03*
X453633Y1102000D03*
X462133Y1575000D03*
X462033Y1656300D03*
X462133Y1718500D03*
X462082Y1709451D03*
X449189Y1774189D03*
X473033Y137200D03*
X465333Y318700D03*
X492333Y385100D03*
X491533Y430600D03*
X492033Y412900D03*
X490833Y421900D03*
X500033Y427200D03*
X495133Y510500D03*
X506533Y536300D03*
X512752Y581742D03*
X512033Y574500D03*
X499533Y565500D03*
X472470Y650145D03*
X478798Y642933D03*
X466133Y605000D03*
X515193Y695200D03*
X515133Y689900D03*
X486333Y667884D03*
X494133Y775000D03*
Y766000D03*
X472233Y866100D03*
X505633Y900500D03*
X495033Y900000D03*
X493233Y904800D03*
X514633Y1009500D03*
X502133Y966000D03*
X496033Y969100D03*
X489133Y966800D03*
X510633Y985900D03*
X480633Y974100D03*
X466333Y1091700D03*
X481233Y1132700D03*
X500133Y1232600D03*
X488633Y1627500D03*
X493533Y1605900D03*
X482433Y1609200D03*
X491433Y1641300D03*
X490633Y1716500D03*
X501633Y1717000D03*
Y1699000D03*
X515633Y1713610D03*
Y1700110D03*
Y1726000D03*
X508133Y1766500D03*
X500633Y1760000D03*
X501633Y1733000D03*
X516133Y1774110D03*
X510133Y1802000D03*
X502133Y1813000D03*
X501633Y1830000D03*
X501133Y1798000D03*
X515633Y1793110D03*
X486133Y1805500D03*
X513133Y1869600D03*
X504633Y1838500D03*
X502133Y1847000D03*
X514233Y1844500D03*
X514833Y1852300D03*
X511133Y1915000D03*
X495133Y1917000D03*
X547633Y442000D03*
X551633Y429000D03*
X554233Y408900D03*
X544133Y486100D03*
X535633Y469500D03*
X544633Y476700D03*
X526033Y541600D03*
X528933Y545600D03*
X549933Y598700D03*
X541151Y584900D03*
X535471Y580496D03*
X547698Y592846D03*
X523678Y601197D03*
X530933Y557400D03*
X564333Y566400D03*
X525633Y567600D03*
X528711Y605771D03*
X522196Y629134D03*
X520596Y623143D03*
X558133Y653600D03*
X551221Y665912D03*
X548433Y656600D03*
X540533Y658500D03*
X554335Y657500D03*
X534633Y732000D03*
X524633Y728000D03*
X546633Y724500D03*
X538133Y809500D03*
X548433Y837000D03*
X521833Y858100D03*
X521533Y848900D03*
X532533Y838300D03*
X527833Y877100D03*
X521933Y865300D03*
X540233Y876700D03*
X537333Y953500D03*
X542117Y946835D03*
X549187Y945600D03*
X560036Y958178D03*
X562633Y953000D03*
X523633Y950500D03*
X539533Y997850D03*
X548213Y992900D03*
X556833Y998400D03*
X516733Y965900D03*
X519675Y987958D03*
X527091Y966958D03*
X532633Y966500D03*
X560033Y1003400D03*
X520633Y1030500D03*
X557633Y1076800D03*
X551995Y1385500D03*
X558133Y1416425D03*
X528633Y1407500D03*
X529133Y1443000D03*
X540966Y1469667D03*
X530133Y1460750D03*
X542157Y1452079D03*
X546255Y1448001D03*
X546328Y1456070D03*
X550471Y1452021D03*
X546157Y1452000D03*
X565233Y1463900D03*
X529333Y1433800D03*
X563533Y1454300D03*
X528833Y1450700D03*
X562133Y1447600D03*
X532133Y1429500D03*
X552133Y1431300D03*
X556108Y1435400D03*
X556433Y1468800D03*
X546633Y1519500D03*
X533466Y1498167D03*
X559313Y1486680D03*
X565633Y1481425D03*
X527133Y1564700D03*
X549633Y1606000D03*
X518633Y1610000D03*
X565633Y1651000D03*
X537633Y1727000D03*
X527633Y1717000D03*
Y1696500D03*
X528133Y1707000D03*
X538633Y1719500D03*
X539133Y1709500D03*
X538633Y1699000D03*
X548633Y1710110D03*
Y1696610D03*
Y1725110D03*
X540633Y1768500D03*
X546633Y1732000D03*
X548633Y1760000D03*
X526633Y1775500D03*
X537401Y1777300D03*
X548633Y1747110D03*
X567133Y1824000D03*
X539633Y1801000D03*
X517633Y1785000D03*
X526633Y1796000D03*
X527133Y1786000D03*
X536901Y1789110D03*
X549133Y1811500D03*
X548633Y1796500D03*
X566133Y1877500D03*
X543133Y1843500D03*
X526133Y1850500D03*
X549633Y1836500D03*
Y1850500D03*
X537633Y1851610D03*
X591745Y438169D03*
X572533Y408200D03*
X573533Y470800D03*
X578133Y522500D03*
X603933Y532200D03*
X580633Y533000D03*
X593333Y541900D03*
X578633Y574600D03*
X574363Y571700D03*
X592233Y604717D03*
X603233Y652900D03*
X605433Y608635D03*
X586333Y620800D03*
X575796Y634051D03*
X577728Y618300D03*
X580468Y640400D03*
X574333Y644600D03*
X582333Y653200D03*
X608150Y620013D03*
X602133Y691000D03*
X571133Y701000D03*
X587633Y695000D03*
X574633Y675000D03*
X596733Y703300D03*
X574133Y711750D03*
X589633Y916500D03*
X568633Y951500D03*
X572233Y1007100D03*
X591133Y1027000D03*
X615133Y1133000D03*
X607633Y1268500D03*
X588907Y1414374D03*
X594633Y1450600D03*
X567133Y1448500D03*
X571533Y1499900D03*
X577633Y1479500D03*
X568133Y1696500D03*
Y1712500D03*
X567633Y1727500D03*
X610633Y1716500D03*
X587633D03*
X596633Y1716000D03*
X611133Y1726000D03*
Y1704000D03*
X597633Y1705000D03*
X587633D03*
X613633Y1696500D03*
X592133Y1697000D03*
X603401Y1697110D03*
X581133D03*
Y1710610D03*
Y1725610D03*
X614133Y1738500D03*
X612733Y1765100D03*
X598133Y1781500D03*
X591633Y1773000D03*
X581633Y1771110D03*
X602401Y1776000D03*
X568133Y1800500D03*
X585633Y1782000D03*
X584633Y1798500D03*
X595633Y1798000D03*
X608133Y1798500D03*
X614633Y1804500D03*
X615133Y1790000D03*
X591133D03*
X601901Y1790110D03*
X581133D03*
X568133Y1851000D03*
X567633Y1839500D03*
X614133Y1852500D03*
X590633D03*
X612233Y1838300D03*
X602133Y1852610D03*
X580633Y1851110D03*
X568994Y1889461D03*
X619061Y435800D03*
X626633Y481500D03*
X618133Y1432000D03*
G54D90*
X461633Y321300D03*
X462633Y1083600D03*
X451133Y1644300D03*
X450933Y1720700D03*
X452733Y1692800D03*
X489433Y155300D03*
Y163300D03*
Y179300D03*
Y159300D03*
Y175300D03*
X479033Y213400D03*
X490333Y217000D03*
X489433Y199300D03*
X465333Y272300D03*
X503333Y431300D03*
X493533Y577200D03*
X511089Y690465D03*
X513233Y686400D03*
X477933Y916400D03*
X501233Y999800D03*
X481933Y1769800D03*
X520836Y61502D03*
X518333Y71500D03*
X550433Y437500D03*
X558489Y692165D03*
X558389Y688065D03*
Y683665D03*
X545433Y670600D03*
X516529Y848500D03*
Y844100D03*
Y852900D03*
X516533Y857200D03*
Y865700D03*
Y861500D03*
X544433Y1408200D03*
X523833Y1451000D03*
X542233Y1425900D03*
X523833Y1439000D03*
X516833Y1484000D03*
X561333Y1482000D03*
X592433Y545600D03*
X595233Y622700D03*
X584862Y615065D03*
X604333Y701100D03*
X584629Y1419200D03*
Y1415000D03*
X573033Y1458400D03*
X584633Y1423400D03*
X623333Y439500D03*
G54D60*
X506533Y980050D03*
Y976300D03*
Y972550D03*
X517133D03*
Y976300D03*
Y980050D03*
G54D42*
X497131Y53103D03*
X496531Y67603D03*
X489733Y191600D03*
X491733Y245800D03*
X490133Y236600D03*
X490733Y207900D03*
X483433Y259900D03*
X487433D03*
X466333Y253500D03*
X502833Y539900D03*
X507733Y571100D03*
X503033Y555400D03*
X468133Y577900D03*
X506333Y702500D03*
X506133Y727400D03*
X472533Y892700D03*
X510531Y1122703D03*
X492631Y1120403D03*
X492331Y1138603D03*
X477433Y1752300D03*
X565912Y539671D03*
X545933Y585196D03*
X558033D03*
X520433Y569800D03*
X565812Y553771D03*
X558468Y658629D03*
X562668D03*
X534033Y658800D03*
X544733Y656800D03*
X545433Y667200D03*
X548733Y828400D03*
X540333D03*
X532033Y828396D03*
X550804Y936356D03*
X546433Y936300D03*
X539633D03*
X565133Y944400D03*
X560633D03*
X552433Y997900D03*
X548433D03*
X543933D03*
X528133Y976300D03*
X564133Y999800D03*
X552133Y1420800D03*
X556633D03*
X547133D03*
X524733Y1420300D03*
X524633Y1460800D03*
X566133Y1498300D03*
X562133D03*
X558133D03*
X554133D03*
X550133D03*
X546133D03*
X542133D03*
X538133D03*
X522633Y1475800D03*
X574433Y578800D03*
X582633Y566600D03*
X580468Y632429D03*
X577568Y649929D03*
X573368D03*
X583633Y699300D03*
X596833Y696200D03*
X587633Y699300D03*
X578133Y945800D03*
X582133D03*
X586133D03*
X574133D03*
X569633Y944400D03*
X568233Y999700D03*
X585764Y1427681D03*
X589964Y1426881D03*
X581464Y1427681D03*
X577633Y1470700D03*
X594533Y1426800D03*
X580133Y1487800D03*
X575633D03*
X571133D03*
X567033Y1487700D03*
G54D51*
X498768Y361900D03*
X539868Y361800D03*
X569598D03*
X528498Y361900D03*
X616698Y1507700D03*
X586968D03*
G54D15*
X460432Y230866D03*
Y220866D03*
Y210866D03*
Y348563D03*
Y338563D03*
Y358563D03*
Y903917D03*
Y923917D03*
Y913917D03*
Y1064587D03*
Y1054587D03*
Y1044587D03*
Y1619941D03*
Y1609941D03*
Y1629941D03*
Y1757638D03*
Y1747638D03*
Y1737638D03*
G54D33*
X461492Y1680500D03*
X489774D03*
G54D65*
X452033Y397800D03*
Y418300D03*
X448233Y667000D03*
X465733Y1551500D03*
X510233Y398500D03*
X476833Y397800D03*
X510233Y419000D03*
X476833Y418300D03*
X473033Y667000D03*
X502733Y798400D03*
X492833Y1090600D03*
X517633D03*
X490533Y1551500D03*
X567033Y88500D03*
X542233D03*
X535033Y398500D03*
Y419000D03*
X527533Y798400D03*
X614433Y397900D03*
X589633D03*
X614333Y356700D03*
X589533D03*
X614533Y376900D03*
X589733D03*
X614433Y418400D03*
X589633D03*
X614033Y1531500D03*
X589233D03*
X614133Y1551600D03*
X589333D03*
G54D59*
X518568Y642629D03*
Y635029D03*
X518633Y1461700D03*
Y1469300D03*
X601233Y549100D03*
Y541500D03*
X581398Y601371D03*
X599233Y607600D03*
Y615200D03*
X581398Y608971D03*
X596133Y1457700D03*
Y1465300D03*
G54D61*
X499335Y1138347D03*
Y1125047D03*
X470733Y1767550D03*
Y1754250D03*
X517635Y1136247D03*
Y1122947D03*
G54D38*
X450483Y1781000D03*
X463783D03*
X507086Y54502D03*
X500783Y584000D03*
X487483D03*
X474183Y593000D03*
X487483D03*
X510983Y715400D03*
X510483Y740400D03*
X489283Y1011800D03*
X502583D03*
X493583Y1032100D03*
X506883D03*
X520386Y54502D03*
X524983Y68500D03*
X538283D03*
X524283Y715400D03*
X523783Y740400D03*
G54D34*
X457033Y246900D03*
X454433Y328500D03*
X465433D03*
X445333Y1657100D03*
X456333D03*
X444933Y1699200D03*
X455933D03*
X468033Y246900D03*
X553829Y1392300D03*
X564829D03*
X535133Y1387500D03*
X546133D03*
X583133D03*
X572133D03*
G54D52*
X498133Y440000D03*
X503133D03*
X508133D03*
X513133D03*
X489533Y1575600D03*
X494533D03*
X499533D03*
X504533D03*
X525633Y439500D03*
X530633D03*
X535633D03*
X540633D03*
X557633Y1575500D03*
X562633D03*
X522633D03*
X527633D03*
X532633D03*
X537633D03*
X570133Y439500D03*
X575133D03*
X580133D03*
X585133D03*
X598133D03*
X603133D03*
X608133D03*
X613133D03*
X591633Y1575500D03*
X596633D03*
X601633D03*
X606633D03*
X567633D03*
X572633D03*
G54D43*
X500935Y56547D03*
X500533Y71754D03*
X504333Y741500D03*
X504833Y719100D03*
X482933Y1013100D03*
X532633Y597500D03*
X575498Y611321D03*
G54D93*
X463533Y294300D03*
X507380Y61398D03*
X479733Y252800D03*
X515062Y533679D03*
X497033Y591000D03*
X500133Y986600D03*
X491133Y1025000D03*
X540433Y380100D03*
X530633Y986000D03*
Y990800D03*
X518333Y1455500D03*
X530333Y1474500D03*
X589433Y532100D03*
X589233Y553300D03*
X605554Y613535D03*
X583833Y1462500D03*
G54D62*
X509333Y1477500D03*
X536733Y558300D03*
X544333D03*
X516933Y1477500D03*
X535903Y1480640D03*
X528303D03*
X612833Y1606500D03*
X609833Y1641000D03*
X617433D03*
X620433Y1606500D03*
G54D80*
X579133Y64500D03*
X581633Y1906000D03*
G54D37*
X522339Y677415D03*
Y682415D03*
Y687415D03*
Y692415D03*
X542439D03*
Y687415D03*
Y682415D03*
Y677415D03*
G54D53*
X501133Y473548D03*
Y491452D03*
X519133Y473548D03*
Y491452D03*
X605133Y473048D03*
Y490952D03*
X587133Y473048D03*
Y490952D03*
G54D29*
X462533Y570800D03*
X456833Y1106000D03*
X451133Y1640200D03*
X463233Y1774400D03*
X452433Y1769600D03*
X499833Y63500D03*
X489433Y171300D03*
Y183300D03*
Y167300D03*
Y187300D03*
X490333Y221000D03*
X479033Y217400D03*
X465215Y264217D03*
X489433Y280000D03*
X511077Y694635D03*
X512533Y682200D03*
X497833Y730000D03*
X501233Y1004300D03*
X492133Y1020600D03*
X504833Y1025400D03*
X504933Y1020900D03*
X470533Y1096000D03*
X501333Y1175100D03*
X467533Y1788200D03*
X531233Y549600D03*
X516233Y569900D03*
X523833Y671000D03*
X548133Y660200D03*
X537433Y662200D03*
X520333Y707900D03*
X518833Y733400D03*
X542233Y1421600D03*
X536633Y1408100D03*
X562333Y1428300D03*
X523833Y1446500D03*
X582633Y430800D03*
X577833Y568000D03*
X585333Y587000D03*
X595233Y626700D03*
X606833Y624300D03*
X580537Y1394000D03*
X573033Y1466400D03*
Y1462400D03*
X572733Y1453300D03*
X589833Y1458000D03*
G54D35*
X462733Y1769900D03*
X510433Y71500D03*
X492933Y662300D03*
Y657600D03*
X483433Y1764700D03*
X544933Y769100D03*
Y764100D03*
X534433Y1058400D03*
Y1053700D03*
X617033Y1652700D03*
Y1648000D03*
X576580Y1878698D03*
X576533Y1883700D03*
G54D44*
X500935Y52947D03*
X500533Y68154D03*
X504333Y737900D03*
X504833Y715500D03*
X482933Y1009500D03*
X532633Y593900D03*
X575498Y607721D03*
G54D96*
X464133Y581300D03*
X487233Y1030800D03*
X516533Y574100D03*
X578633Y578600D03*
X593733Y608500D03*
X579633Y699200D03*
G54D86*
X508033Y1498700D03*
Y1523500D03*
X553431Y1883503D03*
Y1908303D03*
X574931Y1151303D03*
Y1126503D03*
G54D81*
X600503Y634819D03*
X588933D03*
X600503Y645839D03*
X588933D03*
G54D45*
X476377Y68110D03*
Y501338D03*
Y761181D03*
Y1207323D03*
Y1467165D03*
Y1900393D03*
G54D30*
X563842Y710500D03*
X546424D03*
G54D54*
X514533Y544750D03*
X512563D03*
X510598D03*
Y561050D03*
X512563D03*
X514533D03*
X518468Y544750D03*
X516503D03*
Y561050D03*
X518468D03*
X537843Y612629D03*
X539808D03*
X541778D03*
X543748D03*
X545713D03*
X547683D03*
X549653D03*
X551623D03*
X553588D03*
X555558D03*
X557528D03*
X559493D03*
Y646029D03*
X557528D03*
X555558D03*
X553588D03*
X551623D03*
X549653D03*
X547683D03*
X545713D03*
X543748D03*
X541778D03*
X539808D03*
X537843D03*
X582268Y542950D03*
X580303D03*
X578333D03*
X576363D03*
X574398D03*
Y559250D03*
X576363D03*
X578333D03*
X580303D03*
X582268D03*
G54D36*
X457133Y1769900D03*
X504833Y71500D03*
X487333Y662300D03*
Y657600D03*
X477833Y1764700D03*
X539333Y769100D03*
Y764100D03*
X528833Y1058400D03*
Y1053700D03*
X611433Y1652700D03*
Y1648000D03*
X570980Y1878698D03*
X570933Y1883700D03*
G54D28*
X461815Y264217D03*
X459133Y570800D03*
X453433Y1106000D03*
X447733Y1640200D03*
X459833Y1774400D03*
X449033Y1769600D03*
X464133Y1788200D03*
X496433Y63500D03*
X486033Y171300D03*
Y183300D03*
Y167300D03*
Y187300D03*
X486933Y221000D03*
X475633Y217400D03*
X486033Y280000D03*
X512833Y569900D03*
X507677Y694635D03*
X509133Y682200D03*
X515433Y733400D03*
X494433Y730000D03*
X497833Y1004300D03*
X488733Y1020600D03*
X501433Y1025400D03*
X501533Y1020900D03*
X467133Y1096000D03*
X497933Y1175100D03*
X527833Y549600D03*
X520433Y671000D03*
X544733Y660200D03*
X534033Y662200D03*
X516933Y707900D03*
X538833Y1421600D03*
X533233Y1408100D03*
X558933Y1428300D03*
X520433Y1446500D03*
X579233Y430800D03*
X574433Y568000D03*
X581933Y587000D03*
X591833Y626700D03*
X603433Y624300D03*
X577137Y1394000D03*
X569633Y1466400D03*
Y1462400D03*
X569333Y1453300D03*
X586433Y1458000D03*
G54D95*
X459433Y1787800D03*
X493633Y573000D03*
X511033Y966200D03*
X500333Y1144500D03*
X516133Y1143000D03*
X523933Y1431500D03*
Y1434900D03*
X562433Y1432000D03*
X523933Y1442800D03*
X592533Y549300D03*
X573433Y695500D03*
G54D91*
X461833Y253500D03*
X448416Y307282D03*
X462033Y1660800D03*
X455033Y1721700D03*
X485733Y191600D03*
X486533Y207900D03*
X486033Y236600D03*
X492133Y264300D03*
X468333Y343800D03*
X510533Y530500D03*
X507533Y587600D03*
X478733Y573500D03*
X490533Y673400D03*
X486533D03*
X493233Y909400D03*
X506135Y1134497D03*
X512633Y1461800D03*
X525233Y530500D03*
X554033Y585204D03*
X549933D03*
X522198Y594071D03*
X526398D03*
X521598Y606971D03*
X524333Y662300D03*
X540033Y881400D03*
X531733D03*
X548433D03*
X551662Y952344D03*
X546662D03*
X541662D03*
X529633Y1420300D03*
X520633D03*
X534133D03*
X564133Y1408404D03*
X563833Y1400604D03*
X536633Y1486800D03*
X599733Y529100D03*
X584733Y529000D03*
X587133Y575200D03*
X599333Y623700D03*
X609498Y642371D03*
X566898Y658671D03*
X583633Y683800D03*
X578633Y708300D03*
X577033Y999700D03*
X581233Y999800D03*
X592633Y994300D03*
X588633D03*
X572933Y999800D03*
X566633Y1440300D03*
G54D89*
X464133Y584900D03*
X487233Y1034400D03*
X516533Y577700D03*
X578633Y582200D03*
X593733Y612100D03*
X579633Y702800D03*
G54D64*
X500383Y1613297D03*
Y1619703D03*
X559383Y1613297D03*
Y1619703D03*
X530883Y1613297D03*
Y1619703D03*
X586883Y1613297D03*
Y1619703D03*
G54D46*
X509842Y119409D03*
Y329409D03*
X578739Y119409D03*
Y329409D03*
G54D73*
X545308Y846304D03*
X542753D03*
X540193D03*
X537633D03*
X535073D03*
X532513D03*
X529958D03*
Y868504D03*
X532513D03*
X535073D03*
X537633D03*
X540193D03*
X542753D03*
X545308D03*
X550773Y963000D03*
X548213D03*
X545653D03*
X543093D03*
Y985200D03*
X545653D03*
X548213D03*
X550773D03*
X584958Y732304D03*
X587513D03*
X590073D03*
X592633D03*
X595193D03*
X597753D03*
X600308D03*
Y710104D03*
X597753D03*
X595193D03*
X592633D03*
X590073D03*
X587513D03*
X584958D03*
X566473Y959500D03*
X569033D03*
X571593D03*
X574153D03*
X576713D03*
X579273D03*
X581833D03*
X584393D03*
Y981700D03*
X581833D03*
X579273D03*
X576713D03*
X574153D03*
X571593D03*
X569033D03*
X566473D03*
G54D82*
X609598Y631371D03*
Y634971D03*
G54D55*
X503033Y550100D03*
X565904Y548521D03*
X561868Y593429D03*
X554968Y593629D03*
X561068Y601929D03*
X534133Y603200D03*
X531033Y654100D03*
X522104Y617335D03*
X546233Y1430100D03*
X573462Y598765D03*
X569062Y604165D03*
X569268Y593229D03*
X589833Y615900D03*
X580162Y627565D03*
X585833Y626800D03*
X608133Y706500D03*
X576733Y994600D03*
X583133Y994500D03*
X571133D03*
G54D94*
X525590Y1773425D03*
G54D88*
X455833Y1787800D03*
X490033Y573000D03*
X507433Y966200D03*
X512533Y1143000D03*
X496733Y1144500D03*
X520333Y1431500D03*
Y1434900D03*
X558833Y1432000D03*
X520333Y1442800D03*
X588933Y549300D03*
X569833Y695500D03*
G54D57*
X465383Y690560D03*
Y688000D03*
Y685440D03*
X480883Y690560D03*
Y688000D03*
Y685440D03*
X487383D03*
Y690560D03*
X471883Y685440D03*
Y690560D03*
G54D83*
X570233Y1401696D03*
Y1410096D03*
X587733Y1446404D03*
Y1438004D03*
G54D74*
X542933Y1397140D03*
Y1399700D03*
Y1402260D03*
X535533D03*
Y1399700D03*
Y1397140D03*
G54D47*
X509842Y139409D03*
Y309409D03*
X578739Y139409D03*
Y309409D03*
G54D56*
X502536Y606702D03*
Y633502D03*
X551230Y1125298D03*
Y1152098D03*
X527630Y1883198D03*
Y1909998D03*
G54D84*
X576633Y1437250D03*
X572758Y1444750D03*
X580508D03*
G54D63*
X496008Y674606D03*
X498568D03*
X501128D03*
Y681106D03*
X496008D03*
G54D66*
X477333Y1760300D03*
X527733Y553300D03*
X515933Y537800D03*
X525233D03*
X542033Y603500D03*
X536733Y593700D03*
X599733Y536400D03*
X590033Y536500D03*
G54D75*
X554133Y1409454D03*
X550258Y1401954D03*
X558008D03*
G54D39*
X501333Y86200D03*
X501735Y757897D03*
X492833Y1050100D03*
X528133Y86200D03*
X528535Y757897D03*
X519633Y1050100D03*
G54D48*
X509842Y161889D03*
Y171889D03*
Y181889D03*
Y191889D03*
Y204409D03*
Y214409D03*
Y224409D03*
Y234409D03*
Y244409D03*
Y256929D03*
Y266929D03*
Y276929D03*
Y286929D03*
X539842Y161889D03*
Y171889D03*
X529842Y161889D03*
Y171889D03*
X519842Y161889D03*
Y171889D03*
X539842Y181889D03*
Y191889D03*
X529842Y181889D03*
Y191889D03*
X519842Y181889D03*
Y191889D03*
X539842Y204409D03*
Y214409D03*
Y224409D03*
Y234409D03*
Y244409D03*
X529842Y204409D03*
Y214409D03*
Y224409D03*
Y234409D03*
Y244409D03*
X519842Y204409D03*
Y214409D03*
Y224409D03*
Y234409D03*
Y244409D03*
X539842Y256929D03*
Y266929D03*
X529842Y256929D03*
Y266929D03*
X519842Y256929D03*
Y266929D03*
X539842Y276929D03*
Y286929D03*
X529842Y276929D03*
Y286929D03*
X519842Y276929D03*
Y286929D03*
X608739Y161889D03*
Y171889D03*
X598739Y161889D03*
Y171889D03*
X588739Y161889D03*
Y171889D03*
X578739Y161889D03*
Y171889D03*
X608739Y181889D03*
Y191889D03*
X598739Y181889D03*
Y191889D03*
X588739Y181889D03*
Y191889D03*
X578739Y181889D03*
Y191889D03*
X608739Y204409D03*
Y214409D03*
Y224409D03*
Y234409D03*
Y244409D03*
X598739Y204409D03*
Y214409D03*
Y224409D03*
Y234409D03*
Y244409D03*
X588739Y204409D03*
Y214409D03*
Y224409D03*
Y234409D03*
Y244409D03*
X578739Y204409D03*
Y214409D03*
Y224409D03*
Y234409D03*
Y244409D03*
X608739Y256929D03*
Y266929D03*
X598739Y256929D03*
Y266929D03*
X588739Y256929D03*
Y266929D03*
X578739Y256929D03*
Y266929D03*
X608739Y276929D03*
Y286929D03*
X598739Y276929D03*
Y286929D03*
X588739Y276929D03*
Y286929D03*
X578739Y276929D03*
Y286929D03*
G54D58*
X479033Y883800D03*
Y894800D03*
X492933Y986600D03*
Y975600D03*
X468133Y1022500D03*
Y1033500D03*
X525133Y931000D03*
Y942000D03*
X576133Y732000D03*
Y721000D03*
G54D76*
X541015Y1461600D03*
X543574D03*
X546133D03*
X548692D03*
X551251D03*
Y1442400D03*
X548692D03*
X546133D03*
X543574D03*
X541015D03*
G54D85*
X571433Y1471800D03*
Y1480800D03*
G54D49*
X476631Y238899D03*
X481333Y238900D03*
X491833Y254200D03*
X474233Y577300D03*
X510633Y727600D03*
X492335Y1128347D03*
X533033Y476600D03*
X525433Y557700D03*
X558198Y673094D03*
X552598D03*
X554033Y722600D03*
X523633Y976700D03*
X559933Y975800D03*
X562633Y1471200D03*
X575833Y476700D03*
X592433Y696500D03*
X573433Y1111300D03*
X578135Y1111347D03*
G54D67*
X480933Y1760300D03*
X531333Y553300D03*
X519533Y537800D03*
X528833D03*
X545633Y603500D03*
X540333Y593700D03*
X603333Y536400D03*
X593633Y536500D03*
G54D87*
X515832Y949600D03*
X493034D03*
G54D68*
X525590Y1747835D03*
Y1823031D03*
X608070Y1328740D03*
X590550Y1747835D03*
Y1823031D03*
G54D77*
X555733Y1457118D03*
Y1454559D03*
Y1452000D03*
Y1449441D03*
Y1446882D03*
X536533D03*
Y1449441D03*
Y1452000D03*
Y1454559D03*
Y1457118D03*
G54D78*
X546133Y1452000D03*
G54D69*
X565368Y618504D03*
Y620469D03*
Y622439D03*
Y624409D03*
Y626374D03*
Y628344D03*
Y630314D03*
Y632284D03*
Y634249D03*
Y636219D03*
Y638189D03*
Y640154D03*
X531968D03*
Y638189D03*
Y636219D03*
Y634249D03*
Y632284D03*
Y630314D03*
Y628344D03*
Y626374D03*
Y624409D03*
Y622439D03*
Y620469D03*
Y618504D03*
G54D79*
X590550Y1773425D03*
G54D204*
X-40574Y1711604D03*
X-27157Y1657822D03*
X-40774Y304304D03*
X-33774Y243404D03*
X-64474Y1773504D03*
X-65274Y1757204D03*
X-64774Y1728504D03*
X-70874Y1700804D03*
X-47074Y1621304D03*
X-89274Y1434604D03*
X-86274Y1377504D03*
X-57474Y1391604D03*
X-69274Y1291704D03*
X-65274D03*
X-71974Y1055704D03*
X-84876Y830607D03*
X-91374Y503304D03*
X-103974Y1434604D03*
X-132774Y1379900D03*
X-128674D03*
X-100939Y1371033D03*
X-105139D03*
X-100339Y1358133D03*
X-103074Y1302804D03*
X-118774Y1083704D03*
X-110474D03*
X-127174D03*
X-130403Y1012760D03*
X-125403D03*
X-120403D03*
X-142874Y556700D03*
X-142574Y564500D03*
X-108374Y544804D03*
X-99374D03*
X-112874D03*
X-115374Y478304D03*
X-178474Y1436004D03*
X-163474Y1436104D03*
X-165874Y1389904D03*
X-178074Y1341404D03*
X-188239Y1322733D03*
X-145639Y1306433D03*
X-162374Y1281304D03*
X-157374Y1256804D03*
X-155774Y965404D03*
X-159974Y965304D03*
X-171374Y970804D03*
X-167374D03*
X-151674Y965304D03*
X-145374Y524804D03*
G54D205*
X-40674Y1696204D03*
X-36974Y1647204D03*
X-37974Y884904D03*
X-26474Y324204D03*
X-26274Y247804D03*
X-28074Y275704D03*
X-93674Y1897004D03*
X-64774Y1813204D03*
Y1805204D03*
Y1789204D03*
Y1809204D03*
Y1793204D03*
X-54374Y1755104D03*
X-65674Y1751504D03*
X-64774Y1769204D03*
X-78674Y1537204D03*
X-68874Y1391304D03*
X-86430Y1278039D03*
X-88574Y1282104D03*
X-91870Y1120004D03*
Y1124404D03*
Y1115604D03*
X-91874Y1111304D03*
Y1102804D03*
Y1107004D03*
X-53274Y1052104D03*
X-76574Y968704D03*
X-92174Y484504D03*
X-57274Y198704D03*
X-96177Y1907002D03*
X-125774Y1531004D03*
X-133830Y1276339D03*
X-133730Y1280439D03*
Y1284839D03*
X-120774Y1297904D03*
X-119774Y560304D03*
X-99174Y517504D03*
X-117574Y542604D03*
X-99174Y529504D03*
X-136674Y486504D03*
X-167774Y1422904D03*
X-170574Y1345804D03*
X-160203Y1353439D03*
X-179674Y1267404D03*
X-159970Y549304D03*
Y553504D03*
X-148374Y510104D03*
X-159974Y545104D03*
X-198674Y1529004D03*
G54D206*
X-31974Y1277604D03*
X-36774D03*
X-81974Y1392304D03*
X-73509Y1274598D03*
X-78409D03*
X-89874Y1260304D03*
X-80074Y1257504D03*
X-75074D03*
X-78674Y987104D03*
X-72074Y964404D03*
X-89272Y830751D03*
X-100174Y1090050D03*
X-95374D03*
X-101874Y1005704D03*
X-111374Y988704D03*
X-137774Y976004D03*
X-148274Y1396104D03*
X-166409Y1358825D03*
G54D12*
X-37795Y1943701D03*
Y1857087D03*
Y1510473D03*
Y1423858D03*
Y1250630D03*
Y1164016D03*
X-37874Y804504D03*
X-37795Y717874D03*
Y544646D03*
Y458032D03*
Y111418D03*
Y24803D03*
G54D207*
X-35345Y1705951D03*
X-27595D03*
X-31470Y1713451D03*
X-32799Y1663154D03*
X-40549D03*
X-36674Y1655654D03*
X-43249Y319454D03*
X-35499D03*
X-39374Y326954D03*
X-35166Y253636D03*
X-27416D03*
X-31291Y261136D03*
X-66566Y1058636D03*
X-58816D03*
X-62691Y1066136D03*
X-86626Y355207D03*
Y348801D03*
X-139399Y1245954D03*
X-143274Y1238454D03*
X-145626Y355207D03*
Y348801D03*
X-117126Y355207D03*
Y348801D03*
X-149499Y1286254D03*
X-157249D03*
X-153374Y1278754D03*
X-147149Y1245954D03*
X-146568Y546235D03*
X-154318D03*
X-155899Y567050D03*
X-163649D03*
X-159774Y559550D03*
X-173368Y531035D03*
X-181118D03*
X-177243Y523535D03*
X-150443Y538735D03*
X-173126Y355207D03*
Y348801D03*
G54D13*
X-23780Y1920394D03*
Y1910394D03*
Y1900394D03*
Y1890394D03*
Y1880394D03*
Y1487165D03*
Y1477165D03*
Y1467165D03*
Y1457165D03*
Y1447165D03*
Y1227323D03*
Y1217323D03*
Y1207323D03*
Y1197323D03*
Y1187323D03*
Y781181D03*
Y771181D03*
Y761181D03*
Y751181D03*
Y741181D03*
Y521339D03*
Y511339D03*
Y501339D03*
Y491339D03*
Y481339D03*
Y88110D03*
Y78110D03*
Y68110D03*
Y58110D03*
Y48110D03*
X-146811Y189685D03*
X-136811D03*
X-126811D03*
X-172874Y598004D03*
Y578004D03*
Y588004D03*
G54D208*
X-31974Y1283204D03*
X-36774D03*
X-81974Y1397904D03*
X-89874Y1265904D03*
X-73509Y1280198D03*
X-78409D03*
X-80074Y1263104D03*
X-75074D03*
X-78674Y992704D03*
X-72074Y970004D03*
X-89272Y836351D03*
X-100174Y1095650D03*
X-95374D03*
X-101874Y1011304D03*
X-111374Y994304D03*
X-137774Y981604D03*
X-148274Y1401704D03*
X-166409Y1364425D03*
G54D209*
X-91721Y1907106D03*
X-47874Y1674204D03*
X-64074Y1715704D03*
X-81374Y1377504D03*
X-84474Y981904D03*
X-75474Y943504D03*
X-124774Y1588404D03*
X-99403Y1434825D03*
X-114974Y982504D03*
Y977704D03*
X-102674Y513004D03*
X-114674Y494004D03*
X-173774Y1436404D03*
X-173574Y1415204D03*
X-189895Y1354969D03*
X-168174Y506004D03*
G54D14*
X-35433Y1811024D03*
Y1338583D03*
X-25590Y629921D03*
X-35433Y157481D03*
X-187008Y1889764D03*
X-187007Y1397638D03*
X-187008Y807087D03*
Y78740D03*
G54D210*
X-39742Y879296D03*
Y871546D03*
X-32242Y875421D03*
X-119892Y1401513D03*
Y1393763D03*
X-112392Y1397638D03*
X-119892Y712536D03*
Y704786D03*
X-112392Y708661D03*
G54D211*
X-55372Y1724005D03*
X-60074Y1724004D03*
X-70574Y1708704D03*
X-52974Y1385604D03*
X-89374Y1235304D03*
X-71076Y834557D03*
X-111774Y1486304D03*
X-104174Y1405204D03*
X-136939Y1289810D03*
X-131339D03*
X-132774Y1240304D03*
X-102374Y986204D03*
X-138674Y987104D03*
X-141374Y491704D03*
X-154574Y1486204D03*
X-171174Y1266404D03*
X-152174Y851604D03*
X-156876Y851557D03*
G54D212*
X-75872Y1912001D03*
X-75272Y1897501D03*
X-68474Y1773504D03*
X-68874Y1728504D03*
X-69474Y1757204D03*
X-62174Y1705204D03*
X-66174D03*
X-45074Y1711604D03*
X-70474Y1719304D03*
X-81574Y1425204D03*
X-86474Y1394004D03*
X-81774Y1409704D03*
X-46874Y1387204D03*
X-85074Y1262604D03*
X-84874Y1237704D03*
X-51274Y1072404D03*
X-89272Y842401D03*
X-71372Y844701D03*
X-71072Y826501D03*
X-56174Y212804D03*
X-144653Y1425433D03*
X-124674Y1379908D03*
X-136774D03*
X-99174Y1395304D03*
X-144553Y1411333D03*
X-137209Y1306475D03*
X-141409D03*
X-112774Y1306304D03*
X-123474Y1308304D03*
X-124174Y1297904D03*
X-127474Y1136704D03*
X-119074D03*
X-110774Y1136708D03*
X-129545Y1028748D03*
X-125174Y1028804D03*
X-118374D03*
X-143874Y1020704D03*
X-139374D03*
X-131174Y967204D03*
X-127174D03*
X-122674D03*
X-106874Y988804D03*
X-142874Y965304D03*
X-130874Y544304D03*
X-135374D03*
X-103374Y504304D03*
X-125874Y544304D03*
X-103474Y544804D03*
X-144874Y466804D03*
X-140874D03*
X-136874D03*
X-132874D03*
X-128874D03*
X-124874D03*
X-120874D03*
X-116874D03*
X-101374Y489304D03*
X-153174Y1386304D03*
X-161374Y1398504D03*
X-159209Y1332675D03*
X-156309Y1315175D03*
X-152109D03*
X-162374Y1265804D03*
X-175574Y1268904D03*
X-166374Y1265804D03*
X-156874Y1019304D03*
X-160874D03*
X-164874D03*
X-152874D03*
X-148374Y1020704D03*
X-146974Y965404D03*
X-164505Y537423D03*
X-168705Y538223D03*
X-160205Y537423D03*
X-156374Y494404D03*
X-173274Y538304D03*
X-158874Y477304D03*
X-154374D03*
X-149874D03*
X-145774Y477404D03*
G54D16*
X-26474Y1719404D03*
X-35774Y1699033D03*
X-27884Y1665522D03*
X-18874Y1390504D03*
X-35174Y1375504D03*
X-34974Y1390404D03*
X-32374Y866504D03*
X-40874Y393504D03*
X-40774Y312204D03*
X-40874Y250004D03*
X-40823Y259053D03*
X-27930Y194315D03*
X-51774Y1831304D03*
X-44074Y1649804D03*
X-71074Y1583404D03*
X-70274Y1537904D03*
X-70774Y1555604D03*
X-69574Y1546604D03*
X-78774Y1541304D03*
X-73874Y1458004D03*
X-85274Y1432204D03*
X-91493Y1386762D03*
X-90774Y1394004D03*
X-78274Y1403004D03*
X-51211Y1318359D03*
X-57539Y1325571D03*
X-44874Y1363504D03*
X-93934Y1273304D03*
X-93874Y1278604D03*
X-65074Y1300620D03*
X-72874Y1193504D03*
Y1202504D03*
X-50974Y1102404D03*
X-84374Y1068004D03*
X-73774Y1068504D03*
X-71974Y1063704D03*
X-93374Y959004D03*
X-80874Y1002504D03*
X-74774Y999404D03*
X-67874Y1001704D03*
X-89374Y982604D03*
X-59374Y994404D03*
X-45074Y876804D03*
X-59974Y835804D03*
X-78874Y735904D03*
X-67374Y341004D03*
X-72274Y362604D03*
X-61174Y359304D03*
X-70174Y327204D03*
X-69374Y252004D03*
X-80374Y251504D03*
Y269504D03*
X-94374Y254894D03*
Y268394D03*
Y242504D03*
X-86874Y202004D03*
X-79374Y208504D03*
X-80374Y235504D03*
X-94874Y194394D03*
X-88874Y166504D03*
X-80874Y155504D03*
X-80374Y138504D03*
X-79874Y170504D03*
X-94374Y175394D03*
X-64874Y163004D03*
X-91874Y98904D03*
X-83374Y130004D03*
X-80874Y121504D03*
X-92974Y124004D03*
X-93574Y116204D03*
X-89874Y53504D03*
X-73874Y51504D03*
X-126374Y1526504D03*
X-130374Y1539504D03*
X-132974Y1559604D03*
X-122874Y1482404D03*
X-114374Y1499004D03*
X-123374Y1491804D03*
X-104774Y1426904D03*
X-107674Y1422904D03*
X-128674Y1369804D03*
X-119892Y1383604D03*
X-114212Y1388008D03*
X-126439Y1375658D03*
X-102419Y1367307D03*
X-109674Y1411104D03*
X-143074Y1402104D03*
X-104374Y1400904D03*
X-107452Y1362733D03*
X-100937Y1339370D03*
X-99337Y1345361D03*
X-136874Y1314904D03*
X-129962Y1302592D03*
X-127174Y1311904D03*
X-119274Y1310004D03*
X-133076Y1311004D03*
X-113374Y1236504D03*
X-103374Y1240504D03*
X-125374Y1244004D03*
X-116874Y1159004D03*
X-127174Y1131504D03*
X-100574Y1110404D03*
X-100274Y1119604D03*
X-111274Y1130204D03*
X-106574Y1091404D03*
X-100674Y1103204D03*
X-118974Y1091804D03*
X-116074Y1015004D03*
X-120858Y1021669D03*
X-127928Y1022904D03*
X-138777Y1010326D03*
X-141374Y1015504D03*
X-102374Y1018004D03*
X-118274Y970654D03*
X-126954Y975604D03*
X-135574Y970104D03*
X-95474Y1002604D03*
X-98416Y980546D03*
X-105832Y1001546D03*
X-111374Y1002004D03*
X-138774Y965104D03*
X-99374Y938004D03*
X-136374Y891704D03*
X-130736Y583004D03*
X-136874Y552079D03*
X-107374Y561004D03*
X-107874Y525504D03*
X-119707Y498837D03*
X-108874Y507754D03*
X-120898Y516425D03*
X-124996Y520503D03*
X-125069Y512434D03*
X-129212Y516483D03*
X-124898Y516504D03*
X-143974Y504604D03*
X-108074Y534704D03*
X-142274Y514204D03*
X-107574Y517804D03*
X-140874Y520904D03*
X-110874Y539004D03*
X-130874Y537204D03*
X-134849Y533104D03*
X-135174Y499704D03*
X-125374Y449004D03*
X-112207Y470337D03*
X-138054Y481824D03*
X-144374Y487079D03*
X-105874Y403804D03*
X-128374Y362504D03*
X-97374Y358504D03*
X-144374Y317504D03*
X-116374Y241504D03*
X-106374Y251504D03*
Y272004D03*
X-106874Y261504D03*
X-117374Y249004D03*
X-117874Y259004D03*
X-117374Y269504D03*
X-127374Y258394D03*
Y271894D03*
Y243394D03*
X-119374Y200004D03*
X-125374Y236504D03*
X-127374Y208504D03*
X-105374Y193004D03*
X-116142Y191204D03*
X-127374Y221394D03*
X-145874Y144504D03*
X-118374Y167504D03*
X-96374Y183504D03*
X-105374Y172504D03*
X-105874Y182504D03*
X-115642Y179394D03*
X-127874Y157004D03*
X-127374Y172004D03*
X-144874Y91004D03*
X-121874Y125004D03*
X-104874Y118004D03*
X-128374Y132004D03*
Y118004D03*
X-116374Y116894D03*
X-170486Y1530335D03*
X-151274Y1560304D03*
X-152274Y1497704D03*
X-156874Y1446004D03*
X-182674Y1436304D03*
X-159374Y1435504D03*
X-172074Y1426604D03*
X-157374Y1393904D03*
X-153104Y1396804D03*
X-170974Y1363787D03*
X-181974Y1315604D03*
X-184174Y1359869D03*
X-165074Y1347704D03*
X-154537Y1334453D03*
X-156469Y1350204D03*
X-159209Y1328104D03*
X-153074Y1323904D03*
X-161074Y1315304D03*
X-186891Y1348491D03*
X-180874Y1277504D03*
X-149874Y1267504D03*
X-166374Y1273504D03*
X-153374Y1293504D03*
X-175474Y1265204D03*
X-152874Y1256754D03*
X-168374Y1052004D03*
X-147374Y1017004D03*
X-150974Y961404D03*
X-169874Y941504D03*
X-193874Y835504D03*
X-186374Y700004D03*
X-167648Y554130D03*
X-173374Y517904D03*
X-145874Y520004D03*
X-150274Y468604D03*
X-156374Y489004D03*
X-146874Y272004D03*
Y256004D03*
X-146374Y241004D03*
X-189374Y252004D03*
X-166374D03*
X-175374Y252504D03*
X-189874Y242504D03*
Y264504D03*
X-176374Y263504D03*
X-166374D03*
X-192374Y272004D03*
X-170874Y271504D03*
X-182142Y271394D03*
X-159874D03*
Y257894D03*
Y242894D03*
X-192874Y230004D03*
X-191474Y203404D03*
X-176874Y187004D03*
X-170374Y195504D03*
X-160374Y197394D03*
X-181142Y192504D03*
X-146874Y168004D03*
X-164374Y186504D03*
X-163374Y170004D03*
X-174374Y170504D03*
X-186874Y170004D03*
X-193374Y164004D03*
X-193874Y178504D03*
X-169874D03*
X-180642Y178394D03*
X-159874D03*
X-146874Y117504D03*
X-146374Y129004D03*
X-192874Y116004D03*
X-169374D03*
X-190974Y130204D03*
X-180874Y115894D03*
X-159374Y117394D03*
X-147735Y79043D03*
X-197802Y1532704D03*
X-205374Y1487004D03*
X-196874Y536504D03*
G54D213*
X-40374Y1647204D03*
X-41374Y884904D03*
X-29874Y324204D03*
X-29674Y247804D03*
X-31474Y275704D03*
X-68174Y1813204D03*
Y1805204D03*
Y1789204D03*
Y1809204D03*
Y1793204D03*
X-57774Y1755104D03*
X-69074Y1751504D03*
X-68174Y1769204D03*
X-44074Y1696204D03*
X-82074Y1537204D03*
X-72274Y1391304D03*
X-89830Y1278039D03*
X-91974Y1282104D03*
X-56674Y1052104D03*
X-79974Y968704D03*
X-60674Y198704D03*
X-99577Y1907002D03*
X-97074Y1897004D03*
X-129174Y1531004D03*
X-137230Y1276339D03*
X-137130Y1280439D03*
Y1284839D03*
X-124174Y1297904D03*
X-95270Y1120004D03*
Y1124404D03*
Y1115604D03*
X-95274Y1111304D03*
Y1102804D03*
Y1107004D03*
X-123174Y560304D03*
X-102574Y517504D03*
X-120974Y542604D03*
X-102574Y529504D03*
X-95574Y484504D03*
X-140074Y486504D03*
X-171174Y1422904D03*
X-173974Y1345804D03*
X-163603Y1353439D03*
X-183074Y1267404D03*
X-163370Y549304D03*
Y553504D03*
X-151774Y510104D03*
X-163374Y545104D03*
X-202074Y1529004D03*
G54D214*
X-85274Y988454D03*
Y992204D03*
Y995954D03*
X-95874D03*
Y992204D03*
Y988454D03*
G54D215*
X-75872Y1915401D03*
X-75272Y1900901D03*
X-68474Y1776904D03*
X-70474Y1722704D03*
X-68874Y1731904D03*
X-69474Y1760604D03*
X-62174Y1708604D03*
X-66174D03*
X-45074Y1715004D03*
X-81574Y1428604D03*
X-86474Y1397404D03*
X-81774Y1413104D03*
X-46874Y1390604D03*
X-85074Y1266004D03*
X-84874Y1241104D03*
X-51274Y1075804D03*
X-89272Y845801D03*
X-71372Y848101D03*
X-71072Y829901D03*
X-56174Y216204D03*
X-144653Y1428833D03*
X-124674Y1383308D03*
X-136774D03*
X-99174Y1398704D03*
X-144553Y1414733D03*
X-137209Y1309875D03*
X-141409D03*
X-112774Y1309704D03*
X-123474Y1311704D03*
X-124174Y1301304D03*
X-127474Y1140104D03*
X-119074D03*
X-110774Y1140108D03*
X-129545Y1032148D03*
X-125174Y1032204D03*
X-118374D03*
X-143874Y1024104D03*
X-139374D03*
X-131174Y970604D03*
X-127174D03*
X-122674D03*
X-106874Y992204D03*
X-142874Y968704D03*
X-130874Y547704D03*
X-135374D03*
X-125874D03*
X-103474Y548204D03*
X-103374Y507704D03*
X-144874Y470204D03*
X-140874D03*
X-136874D03*
X-132874D03*
X-128874D03*
X-124874D03*
X-120874D03*
X-116874D03*
X-101374Y492704D03*
X-153174Y1389704D03*
X-161374Y1401904D03*
X-159209Y1336075D03*
X-156309Y1318575D03*
X-152109D03*
X-162374Y1269204D03*
X-175574Y1272304D03*
X-166374Y1269204D03*
X-156874Y1022704D03*
X-160874D03*
X-164874D03*
X-152874D03*
X-148374Y1024104D03*
X-146974Y968804D03*
X-164505Y540823D03*
X-168705Y541623D03*
X-160205Y540823D03*
X-156374Y497804D03*
X-173274Y541704D03*
X-158874Y480704D03*
X-154374D03*
X-149874D03*
X-145774Y480804D03*
G54D216*
X-77509Y1606604D03*
X-118609Y1606704D03*
X-148339D03*
X-107239Y1606604D03*
X-195439Y460804D03*
X-165709D03*
G54D15*
X-39173Y1737638D03*
Y1747638D03*
Y1757638D03*
Y1619941D03*
Y1629941D03*
Y1609941D03*
Y1064587D03*
Y1044587D03*
Y1054587D03*
Y903917D03*
Y913917D03*
Y923917D03*
Y348563D03*
Y358563D03*
Y338563D03*
Y210866D03*
Y220866D03*
Y230866D03*
G54D217*
X-40233Y288004D03*
X-68515D03*
G54D218*
X-30774Y1570704D03*
Y1550204D03*
X-26974Y1301504D03*
X-44474Y417004D03*
X-88974Y1570004D03*
X-55574Y1570704D03*
X-88974Y1549504D03*
X-55574Y1550204D03*
X-51774Y1301504D03*
X-81474Y1170104D03*
X-71574Y877904D03*
X-96374D03*
X-69274Y417004D03*
X-145774Y1880004D03*
X-120974D03*
X-113774Y1570004D03*
Y1549504D03*
X-106274Y1170104D03*
X-193174Y1570604D03*
X-168374D03*
X-193074Y1611804D03*
X-168274D03*
X-193274Y1591604D03*
X-168474D03*
X-193174Y1550104D03*
X-168374D03*
X-192774Y437004D03*
X-167974D03*
X-192874Y416904D03*
X-168074D03*
G54D219*
X-97309Y1325875D03*
Y1333475D03*
X-97374Y506804D03*
Y499204D03*
X-179974Y1419404D03*
Y1427004D03*
X-160139Y1367133D03*
X-177974Y1360904D03*
Y1353304D03*
X-160139Y1359533D03*
X-174874Y510804D03*
Y503204D03*
G54D220*
X-78076Y830157D03*
Y843457D03*
X-49474Y200954D03*
Y214254D03*
X-96376Y832257D03*
Y845557D03*
G54D221*
X-29224Y187504D03*
X-42524D03*
X-85827Y1914002D03*
X-79524Y1384504D03*
X-66224D03*
X-52924Y1375504D03*
X-66224D03*
X-89724Y1253104D03*
X-89224Y1228104D03*
X-68024Y956704D03*
X-81324D03*
X-72324Y936404D03*
X-85624D03*
X-99127Y1914002D03*
X-103724Y1900004D03*
X-117024D03*
X-103024Y1253104D03*
X-102524Y1228104D03*
G54D222*
X-35774Y1721604D03*
X-33174Y1640004D03*
X-44174D03*
X-24074Y311404D03*
X-35074D03*
X-23674Y269304D03*
X-34674D03*
X-46774Y1721604D03*
X-132570Y576204D03*
X-143570D03*
X-113874Y581004D03*
X-124874D03*
X-161874D03*
X-150874D03*
G54D223*
X-76874Y1528504D03*
X-81874D03*
X-86874D03*
X-91874D03*
X-68274Y392904D03*
X-73274D03*
X-78274D03*
X-83274D03*
X-104374Y1529004D03*
X-109374D03*
X-114374D03*
X-119374D03*
X-136374Y393004D03*
X-141374D03*
X-101374D03*
X-106374D03*
X-111374D03*
X-116374D03*
X-148874Y1529004D03*
X-153874D03*
X-158874D03*
X-163874D03*
X-176874D03*
X-181874D03*
X-186874D03*
X-191874D03*
X-170374Y393004D03*
X-175374D03*
X-180374D03*
X-185374D03*
X-146374D03*
X-151374D03*
G54D224*
X-79676Y1911957D03*
X-79274Y1896750D03*
X-83074Y1227004D03*
X-83574Y1249404D03*
X-61674Y955404D03*
X-111374Y1371004D03*
X-154239Y1357183D03*
G54D225*
X-42274Y1674204D03*
X-86121Y1907106D03*
X-58474Y1715704D03*
X-93803Y1434825D03*
X-75774Y1377504D03*
X-78874Y981904D03*
X-69874Y943504D03*
X-119174Y1588404D03*
X-109374Y982504D03*
Y977704D03*
X-97074Y513004D03*
X-109074Y494004D03*
X-168174Y1436404D03*
X-167974Y1415204D03*
X-184295Y1354969D03*
X-162574Y506004D03*
G54D226*
X-88074Y491004D03*
X-115474Y1410204D03*
X-123074D03*
X-95674Y491004D03*
X-114644Y487864D03*
X-107044D03*
X-191574Y362004D03*
X-188574Y327504D03*
X-196174D03*
X-199174Y362004D03*
G54D202*
X-157874Y1904004D03*
X-160374Y62504D03*
G54D227*
X-101080Y1291089D03*
Y1286089D03*
Y1281089D03*
Y1276089D03*
X-121180D03*
Y1281089D03*
Y1286089D03*
Y1291089D03*
G54D228*
X-79874Y1494956D03*
Y1477052D03*
X-97874Y1494956D03*
Y1477052D03*
X-183874Y1495456D03*
Y1477552D03*
X-165874Y1495456D03*
Y1477552D03*
G54D229*
X-41274Y1397704D03*
X-35574Y862504D03*
X-29874Y328304D03*
X-41974Y194104D03*
X-31174Y198904D03*
X-78574Y1905004D03*
X-68174Y1797204D03*
Y1785204D03*
Y1801204D03*
Y1781204D03*
X-69074Y1747504D03*
X-57774Y1751104D03*
X-43956Y1704287D03*
X-68174Y1688504D03*
X-89818Y1273869D03*
X-91274Y1286304D03*
X-76574Y1238504D03*
X-79974Y964204D03*
X-70874Y947904D03*
X-83574Y943104D03*
X-83674Y947604D03*
X-49274Y872504D03*
X-80074Y793404D03*
X-46274Y180304D03*
X-109974Y1418904D03*
X-94974Y1398604D03*
X-102574Y1297504D03*
X-126874Y1308304D03*
X-116174Y1306304D03*
X-99074Y1260604D03*
X-97574Y1235104D03*
X-120974Y546904D03*
X-115374Y560404D03*
X-141074Y540204D03*
X-102574Y522004D03*
X-161374Y1537704D03*
X-156574Y1400504D03*
X-164074Y1381504D03*
X-173974Y1341804D03*
X-185574Y1344204D03*
X-159278Y574504D03*
X-151774Y502104D03*
Y506104D03*
X-151474Y515204D03*
X-168574Y510504D03*
G54D230*
X-41474Y198604D03*
X-89174Y1897004D03*
X-71674Y1306204D03*
Y1310904D03*
X-62174Y203804D03*
X-123674Y1199404D03*
Y1204404D03*
X-113174Y910104D03*
Y914804D03*
X-195774Y315804D03*
Y320504D03*
X-155321Y89806D03*
X-155274Y84804D03*
G54D231*
X-79676Y1915557D03*
X-79274Y1900350D03*
X-83074Y1230604D03*
X-83574Y1253004D03*
X-61674Y959004D03*
X-111374Y1374604D03*
X-154239Y1360783D03*
G54D232*
X-42874Y1387204D03*
X-65974Y937704D03*
X-95274Y1394404D03*
X-157374Y1389904D03*
X-172474Y1360004D03*
X-158374Y1269304D03*
G54D233*
X-86774Y469804D03*
Y445004D03*
X-132172Y85001D03*
Y60201D03*
X-153672Y817201D03*
Y842001D03*
G54D234*
X-179244Y1333685D03*
X-167674D03*
X-179244Y1322665D03*
X-167674D03*
G54D17*
X-55118Y1900394D03*
Y1467166D03*
Y1207323D03*
Y761181D03*
Y501339D03*
Y68111D03*
G54D235*
X-142583Y1258004D03*
X-125165D03*
G54D236*
X-93274Y1423754D03*
X-91304D03*
X-89339D03*
Y1407454D03*
X-91304D03*
X-93274D03*
X-97209Y1423754D03*
X-95244D03*
Y1407454D03*
X-97209D03*
X-116584Y1355875D03*
X-118549D03*
X-120519D03*
X-122489D03*
X-124454D03*
X-126424D03*
X-128394D03*
X-130364D03*
X-132329D03*
X-134299D03*
X-136269D03*
X-138234D03*
Y1322475D03*
X-136269D03*
X-134299D03*
X-132329D03*
X-130364D03*
X-128394D03*
X-126424D03*
X-124454D03*
X-122489D03*
X-120519D03*
X-118549D03*
X-116584D03*
X-161009Y1425554D03*
X-159044D03*
X-157074D03*
X-155104D03*
X-153139D03*
Y1409254D03*
X-155104D03*
X-157074D03*
X-159044D03*
X-161009D03*
G54D237*
X-35874Y198604D03*
X-83574Y1897004D03*
X-66074Y1306204D03*
Y1310904D03*
X-56574Y203804D03*
X-118074Y1199404D03*
Y1204404D03*
X-107574Y910104D03*
Y914804D03*
X-190174Y315804D03*
Y320504D03*
X-149721Y89806D03*
X-149674Y84804D03*
G54D238*
X-40556Y1704287D03*
X-37874Y1397704D03*
X-32174Y862504D03*
X-26474Y328304D03*
X-38574Y194104D03*
X-27774Y198904D03*
X-42874Y180304D03*
X-75174Y1905004D03*
X-64774Y1797204D03*
Y1785204D03*
Y1801204D03*
Y1781204D03*
X-65674Y1747504D03*
X-54374Y1751104D03*
X-64774Y1688504D03*
X-91574Y1398604D03*
X-86418Y1273869D03*
X-87874Y1286304D03*
X-94174Y1235104D03*
X-73174Y1238504D03*
X-76574Y964204D03*
X-67474Y947904D03*
X-80174Y943104D03*
X-80274Y947604D03*
X-45874Y872504D03*
X-76674Y793404D03*
X-106574Y1418904D03*
X-99174Y1297504D03*
X-123474Y1308304D03*
X-112774Y1306304D03*
X-95674Y1260604D03*
X-117574Y546904D03*
X-111974Y560404D03*
X-137674Y540204D03*
X-99174Y522004D03*
X-157974Y1537704D03*
X-153174Y1400504D03*
X-160674Y1381504D03*
X-170574Y1341804D03*
X-182174Y1344204D03*
X-155878Y574504D03*
X-148374Y502104D03*
Y506104D03*
X-148074Y515204D03*
X-165174Y510504D03*
G54D239*
X-38174Y180704D03*
X-72374Y1395504D03*
X-89774Y1002304D03*
X-79074Y824004D03*
X-94874Y825504D03*
X-102674Y537004D03*
Y533604D03*
X-141174Y536504D03*
X-102674Y525704D03*
X-171274Y1419204D03*
X-152174Y1273004D03*
G54D240*
X-40574Y1715004D03*
X-27157Y1661222D03*
X-40774Y307704D03*
X-33774Y246804D03*
X-64474Y1776904D03*
X-65274Y1760604D03*
X-64774Y1731904D03*
X-70874Y1704204D03*
X-47074Y1624704D03*
X-89274Y1438004D03*
X-86274Y1380904D03*
X-57474Y1395004D03*
X-69274Y1295104D03*
X-65274D03*
X-71974Y1059104D03*
X-84876Y834007D03*
X-91374Y506704D03*
X-103974Y1438004D03*
X-132774Y1383300D03*
X-128674D03*
X-100939Y1374433D03*
X-105139D03*
X-100339Y1361533D03*
X-103074Y1306204D03*
X-118774Y1087104D03*
X-110474D03*
X-127174D03*
X-130403Y1016160D03*
X-125403D03*
X-120403D03*
X-108374Y548204D03*
X-99374D03*
X-112874D03*
X-142874Y560100D03*
X-142574Y567900D03*
X-115374Y481704D03*
X-178474Y1439404D03*
X-163474Y1439504D03*
X-165874Y1393304D03*
X-178074Y1344804D03*
X-188239Y1326133D03*
X-145639Y1309833D03*
X-162374Y1284704D03*
X-157374Y1260204D03*
X-155774Y968804D03*
X-159974Y968704D03*
X-171374Y974204D03*
X-167374D03*
X-151674Y968704D03*
X-145374Y528204D03*
G54D241*
X-42874Y1383604D03*
X-65974Y934104D03*
X-95274Y1390804D03*
X-157374Y1386304D03*
X-172474Y1356404D03*
X-158374Y1265704D03*
G54D242*
X-79124Y355207D03*
Y348801D03*
X-138124Y355207D03*
Y348801D03*
X-109624Y355207D03*
Y348801D03*
X-165624Y355207D03*
Y348801D03*
G54D18*
X-88583Y1849095D03*
Y1639095D03*
X-157480Y1849095D03*
Y1639095D03*
G54D243*
X-124049Y1122200D03*
X-121494D03*
X-118934D03*
X-116374D03*
X-113814D03*
X-111254D03*
X-108699D03*
Y1100000D03*
X-111254D03*
X-113814D03*
X-116374D03*
X-118934D03*
X-121494D03*
X-124049D03*
X-129514Y1005504D03*
X-126954D03*
X-124394D03*
X-121834D03*
Y983304D03*
X-124394D03*
X-126954D03*
X-129514D03*
X-163699Y1236200D03*
X-166254D03*
X-168814D03*
X-171374D03*
X-173934D03*
X-176494D03*
X-179049D03*
Y1258400D03*
X-176494D03*
X-173934D03*
X-171374D03*
X-168814D03*
X-166254D03*
X-163699D03*
X-145214Y1009004D03*
X-147774D03*
X-150334D03*
X-152894D03*
X-155454D03*
X-158014D03*
X-160574D03*
X-163134D03*
Y986804D03*
X-160574D03*
X-158014D03*
X-155454D03*
X-152894D03*
X-150334D03*
X-147774D03*
X-145214D03*
G54D244*
X-188339Y1337133D03*
Y1333533D03*
G54D71*
X-81774Y1418404D03*
X-144645Y1419983D03*
X-140609Y1375075D03*
X-133709Y1374875D03*
X-139809Y1366575D03*
X-112874Y1365304D03*
X-109774Y1314404D03*
X-100845Y1351169D03*
X-124974Y538404D03*
X-152203Y1369739D03*
X-147803Y1364339D03*
X-148009Y1375275D03*
X-168574Y1352604D03*
X-158903Y1340939D03*
X-164574Y1341704D03*
X-186874Y1262004D03*
X-155474Y973904D03*
X-161874Y974004D03*
X-149874D03*
G54D245*
X-104331Y195079D03*
G54D246*
X-34574Y180704D03*
X-68774Y1395504D03*
X-86174Y1002304D03*
X-91274Y825504D03*
X-75474Y824004D03*
X-99074Y537004D03*
Y533604D03*
X-137574Y536504D03*
X-99074Y525704D03*
X-167674Y1419204D03*
X-148574Y1273004D03*
G54D247*
X-44124Y1277944D03*
Y1280504D03*
Y1283064D03*
X-59624Y1277944D03*
Y1280504D03*
Y1283064D03*
X-66124D03*
Y1277944D03*
X-50624Y1283064D03*
Y1277944D03*
G54D248*
X-148974Y566808D03*
Y558408D03*
X-166474Y522100D03*
Y530500D03*
G54D249*
X-121674Y571364D03*
Y568804D03*
Y566244D03*
X-114274D03*
Y568804D03*
Y571364D03*
G54D19*
X-88583Y1829095D03*
Y1659095D03*
X-157480Y1829095D03*
Y1659095D03*
G54D250*
X-81277Y1361802D03*
Y1335002D03*
X-129971Y843206D03*
Y816406D03*
X-106371Y85306D03*
Y58506D03*
G54D251*
X-155374Y531254D03*
X-151499Y523754D03*
X-159249D03*
G54D252*
X-74749Y1293898D03*
X-77309D03*
X-79869D03*
Y1287398D03*
X-74749D03*
G54D253*
X-56074Y208204D03*
X-106474Y1415204D03*
X-94674Y1430704D03*
X-103974D03*
X-120774Y1365004D03*
X-115474Y1374804D03*
X-178474Y1432104D03*
X-168774Y1432004D03*
G54D254*
X-132874Y559050D03*
X-128999Y566550D03*
X-136749D03*
G54D255*
X-80074Y1882304D03*
X-80476Y1210607D03*
X-71574Y918404D03*
X-106874Y1882304D03*
X-107276Y1210607D03*
X-98374Y918404D03*
G54D20*
X-88583Y1806615D03*
Y1796615D03*
Y1786615D03*
Y1776615D03*
Y1764095D03*
Y1754095D03*
Y1744095D03*
Y1734095D03*
Y1724095D03*
Y1711575D03*
Y1701575D03*
Y1691575D03*
Y1681575D03*
X-118583Y1806615D03*
Y1796615D03*
X-108583Y1806615D03*
Y1796615D03*
X-98583Y1806615D03*
Y1796615D03*
X-118583Y1786615D03*
Y1776615D03*
X-108583Y1786615D03*
Y1776615D03*
X-98583Y1786615D03*
Y1776615D03*
X-118583Y1764095D03*
Y1754095D03*
Y1744095D03*
Y1734095D03*
Y1724095D03*
X-108583Y1764095D03*
Y1754095D03*
Y1744095D03*
Y1734095D03*
Y1724095D03*
X-98583Y1764095D03*
Y1754095D03*
Y1744095D03*
Y1734095D03*
Y1724095D03*
X-118583Y1711575D03*
Y1701575D03*
X-108583Y1711575D03*
Y1701575D03*
X-98583Y1711575D03*
Y1701575D03*
X-118583Y1691575D03*
Y1681575D03*
X-108583Y1691575D03*
Y1681575D03*
X-98583Y1691575D03*
Y1681575D03*
X-187480Y1806615D03*
Y1796615D03*
X-177480Y1806615D03*
Y1796615D03*
X-167480Y1806615D03*
Y1796615D03*
X-157480Y1806615D03*
Y1796615D03*
X-187480Y1786615D03*
Y1776615D03*
X-177480Y1786615D03*
Y1776615D03*
X-167480Y1786615D03*
Y1776615D03*
X-157480Y1786615D03*
Y1776615D03*
X-187480Y1764095D03*
Y1754095D03*
Y1744095D03*
Y1734095D03*
Y1724095D03*
X-177480Y1764095D03*
Y1754095D03*
Y1744095D03*
Y1734095D03*
Y1724095D03*
X-167480Y1764095D03*
Y1754095D03*
Y1744095D03*
Y1734095D03*
Y1724095D03*
X-157480Y1764095D03*
Y1754095D03*
Y1744095D03*
Y1734095D03*
Y1724095D03*
X-187480Y1711575D03*
Y1701575D03*
X-177480Y1711575D03*
Y1701575D03*
X-167480Y1711575D03*
Y1701575D03*
X-157480Y1711575D03*
Y1701575D03*
X-187480Y1691575D03*
Y1681575D03*
X-177480Y1691575D03*
Y1681575D03*
X-167480Y1691575D03*
Y1681575D03*
X-157480Y1691575D03*
Y1681575D03*
G54D256*
X-57774Y1084704D03*
Y1073704D03*
X-71674Y981904D03*
Y992904D03*
X-46874Y946004D03*
Y935004D03*
X-103874Y1037504D03*
Y1026504D03*
X-154874Y1236504D03*
Y1247504D03*
G54D257*
X-119756Y506904D03*
X-122315D03*
X-124874D03*
X-127433D03*
X-129992D03*
Y526104D03*
X-127433D03*
X-124874D03*
X-122315D03*
X-119756D03*
G54D258*
X-150174Y496704D03*
Y487704D03*
G54D259*
X-55372Y1729605D03*
X-60074Y1729604D03*
X-70574Y1714304D03*
X-52974Y1391204D03*
X-89374Y1240904D03*
X-71076Y840157D03*
X-111774Y1491904D03*
X-104174Y1410804D03*
X-136939Y1295410D03*
X-131339D03*
X-132774Y1245904D03*
X-102374Y991804D03*
X-138674Y992704D03*
X-141374Y497304D03*
X-154574Y1491804D03*
X-171174Y1272004D03*
X-152174Y857204D03*
X-156876Y857157D03*
G54D260*
X-59674Y208204D03*
X-110074Y1415204D03*
X-98274Y1430704D03*
X-107574D03*
X-124374Y1365004D03*
X-119074Y1374804D03*
X-182074Y1432104D03*
X-172374Y1432004D03*
G54D261*
X-94573Y1018904D03*
X-71775D03*
G54D21*
X-104331Y220669D03*
Y145473D03*
X-186811Y639764D03*
X-169291Y220669D03*
Y145473D03*
G54D262*
X-134474Y511386D03*
Y513945D03*
Y516504D03*
Y519063D03*
Y521622D03*
X-115274D03*
Y519063D03*
Y516504D03*
Y513945D03*
Y511386D03*
G54D263*
X-124874Y516504D03*
G54D264*
X-144109Y1350000D03*
Y1348035D03*
Y1346065D03*
Y1344095D03*
Y1342130D03*
Y1340160D03*
Y1338190D03*
Y1336220D03*
Y1334255D03*
Y1332285D03*
Y1330315D03*
Y1328350D03*
X-110709D03*
Y1330315D03*
Y1332285D03*
Y1334255D03*
Y1336220D03*
Y1338190D03*
Y1340160D03*
Y1342130D03*
Y1344095D03*
Y1346065D03*
Y1348035D03*
Y1350000D03*
G54D265*
X-169291Y195079D03*
G54D204*
X388560Y1711604D03*
X401977Y1657822D03*
X388360Y304304D03*
X395360Y243404D03*
X364660Y1773504D03*
X363860Y1757204D03*
X364360Y1728504D03*
X358260Y1700804D03*
X382060Y1621304D03*
X339860Y1434604D03*
X342860Y1377504D03*
X371660Y1391604D03*
X359860Y1291704D03*
X363860D03*
X357160Y1055704D03*
X344258Y830607D03*
X337760Y503304D03*
X325160Y1434604D03*
X296360Y1379900D03*
X300460D03*
X328195Y1371033D03*
X323995D03*
X328795Y1358133D03*
X326060Y1302804D03*
X310360Y1083704D03*
X318660D03*
X301960D03*
X298731Y1012760D03*
X303731D03*
X308731D03*
X286260Y556700D03*
X286560Y564500D03*
X320760Y544804D03*
X329760D03*
X316260D03*
X313760Y478304D03*
X250660Y1436004D03*
X265660Y1436104D03*
X263260Y1389904D03*
X251060Y1341404D03*
X240895Y1322733D03*
X283495Y1306433D03*
X266760Y1281304D03*
X271760Y1256804D03*
X273360Y965404D03*
X269160Y965304D03*
X257760Y970804D03*
X261760D03*
X277460Y965304D03*
X283760Y524804D03*
G54D205*
X388460Y1696204D03*
X392160Y1647204D03*
X391160Y884904D03*
X402660Y324204D03*
X402860Y247804D03*
X401060Y275704D03*
X335460Y1897004D03*
X364360Y1813204D03*
Y1805204D03*
Y1789204D03*
Y1809204D03*
Y1793204D03*
X374760Y1755104D03*
X363460Y1751504D03*
X364360Y1769204D03*
X350460Y1537204D03*
X360260Y1391304D03*
X342704Y1278039D03*
X340560Y1282104D03*
X337264Y1120004D03*
Y1124404D03*
Y1115604D03*
X337260Y1111304D03*
Y1102804D03*
Y1107004D03*
X375860Y1052104D03*
X352560Y968704D03*
X336960Y484504D03*
X371860Y198704D03*
X332957Y1907002D03*
X303360Y1531004D03*
X295304Y1276339D03*
X295404Y1280439D03*
Y1284839D03*
X308360Y1297904D03*
X309360Y560304D03*
X329960Y517504D03*
X311560Y542604D03*
X329960Y529504D03*
X292460Y486504D03*
X261360Y1422904D03*
X258560Y1345804D03*
X268931Y1353439D03*
X249460Y1267404D03*
X269164Y549304D03*
Y553504D03*
X280760Y510104D03*
X269160Y545104D03*
X230460Y1529004D03*
G54D206*
X397160Y1277604D03*
X392360D03*
X347160Y1392304D03*
X355625Y1274598D03*
X350725D03*
X339260Y1260304D03*
X349060Y1257504D03*
X354060D03*
X350460Y987104D03*
X357060Y964404D03*
X339862Y830751D03*
X328960Y1090050D03*
X333760D03*
X327260Y1005704D03*
X317760Y988704D03*
X291360Y976004D03*
X280860Y1396104D03*
X262725Y1358825D03*
G54D12*
X391339Y1943701D03*
Y1857087D03*
Y1510473D03*
Y1423858D03*
Y1250630D03*
Y1164016D03*
X391260Y804504D03*
X391339Y717874D03*
Y544646D03*
Y458032D03*
Y111418D03*
Y24803D03*
G54D207*
X393789Y1705951D03*
X401539D03*
X397664Y1713451D03*
X396335Y1663154D03*
X388585D03*
X392460Y1655654D03*
X385885Y319454D03*
X393635D03*
X389760Y326954D03*
X393968Y253636D03*
X401718D03*
X397843Y261136D03*
X362568Y1058636D03*
X370318D03*
X366443Y1066136D03*
X342508Y355207D03*
Y348801D03*
X289735Y1245954D03*
X285860Y1238454D03*
X283508Y355207D03*
Y348801D03*
X312008Y355207D03*
Y348801D03*
X279635Y1286254D03*
X271885D03*
X275760Y1278754D03*
X281985Y1245954D03*
X282566Y546235D03*
X274816D03*
X273235Y567050D03*
X265485D03*
X269360Y559550D03*
X255766Y531035D03*
X248016D03*
X251891Y523535D03*
X278691Y538735D03*
X256008Y355207D03*
Y348801D03*
G54D13*
X405354Y1920394D03*
Y1910394D03*
Y1900394D03*
Y1890394D03*
Y1880394D03*
Y1487165D03*
Y1477165D03*
Y1467165D03*
Y1457165D03*
Y1447165D03*
Y1227323D03*
Y1217323D03*
Y1207323D03*
Y1197323D03*
Y1187323D03*
Y781181D03*
Y771181D03*
Y761181D03*
Y751181D03*
Y741181D03*
Y521339D03*
Y511339D03*
Y501339D03*
Y491339D03*
Y481339D03*
Y88110D03*
Y78110D03*
Y68110D03*
Y58110D03*
Y48110D03*
X282323Y189685D03*
X292323D03*
X302323D03*
X256260Y598004D03*
Y578004D03*
Y588004D03*
G54D208*
X397160Y1283204D03*
X392360D03*
X347160Y1397904D03*
X339260Y1265904D03*
X355625Y1280198D03*
X350725D03*
X349060Y1263104D03*
X354060D03*
X350460Y992704D03*
X357060Y970004D03*
X339862Y836351D03*
X328960Y1095650D03*
X333760D03*
X327260Y1011304D03*
X317760Y994304D03*
X291360Y981604D03*
X280860Y1401704D03*
X262725Y1364425D03*
G54D209*
X337413Y1907106D03*
X381260Y1674204D03*
X365060Y1715704D03*
X347760Y1377504D03*
X344660Y981904D03*
X353660Y943504D03*
X304360Y1588404D03*
X329731Y1434825D03*
X314160Y982504D03*
Y977704D03*
X326460Y513004D03*
X314460Y494004D03*
X255360Y1436404D03*
X255560Y1415204D03*
X239239Y1354969D03*
X260960Y506004D03*
G54D14*
X393701Y1811024D03*
Y1338583D03*
X403544Y629921D03*
X393701Y157481D03*
X242126Y1889764D03*
X242127Y1397638D03*
X242126Y807087D03*
Y78740D03*
G54D210*
X389392Y879296D03*
Y871546D03*
X396892Y875421D03*
X309242Y1401513D03*
Y1393763D03*
X316742Y1397638D03*
X309242Y712536D03*
Y704786D03*
X316742Y708661D03*
G54D211*
X373762Y1724005D03*
X369060Y1724004D03*
X358560Y1708704D03*
X376160Y1385604D03*
X339760Y1235304D03*
X358058Y834557D03*
X317360Y1486304D03*
X324960Y1405204D03*
X292195Y1289810D03*
X297795D03*
X296360Y1240304D03*
X326760Y986204D03*
X290460Y987104D03*
X287760Y491704D03*
X274560Y1486204D03*
X257960Y1266404D03*
X276960Y851604D03*
X272258Y851557D03*
G54D212*
X353262Y1912001D03*
X353862Y1897501D03*
X360660Y1773504D03*
X360260Y1728504D03*
X359660Y1757204D03*
X366960Y1705204D03*
X362960D03*
X384060Y1711604D03*
X358660Y1719304D03*
X347560Y1425204D03*
X342660Y1394004D03*
X347360Y1409704D03*
X382260Y1387204D03*
X344060Y1262604D03*
X344260Y1237704D03*
X377860Y1072404D03*
X339862Y842401D03*
X357762Y844701D03*
X358062Y826501D03*
X372960Y212804D03*
X284481Y1425433D03*
X304460Y1379908D03*
X292360D03*
X329960Y1395304D03*
X284581Y1411333D03*
X291925Y1306475D03*
X287725D03*
X316360Y1306304D03*
X305660Y1308304D03*
X304960Y1297904D03*
X301660Y1136704D03*
X310060D03*
X318360Y1136708D03*
X299589Y1028748D03*
X303960Y1028804D03*
X310760D03*
X285260Y1020704D03*
X289760D03*
X297960Y967204D03*
X301960D03*
X306460D03*
X322260Y988804D03*
X286260Y965304D03*
X298260Y544304D03*
X293760D03*
X325760Y504304D03*
X303260Y544304D03*
X325660Y544804D03*
X284260Y466804D03*
X288260D03*
X292260D03*
X296260D03*
X300260D03*
X304260D03*
X308260D03*
X312260D03*
X327760Y489304D03*
X275960Y1386304D03*
X267760Y1398504D03*
X269925Y1332675D03*
X272825Y1315175D03*
X277025D03*
X266760Y1265804D03*
X253560Y1268904D03*
X262760Y1265804D03*
X272260Y1019304D03*
X268260D03*
X264260D03*
X276260D03*
X280760Y1020704D03*
X282160Y965404D03*
X264629Y537423D03*
X260429Y538223D03*
X268929Y537423D03*
X272760Y494404D03*
X255860Y538304D03*
X270260Y477304D03*
X274760D03*
X279260D03*
X283360Y477404D03*
G54D16*
X402660Y1719404D03*
X393360Y1699033D03*
X401250Y1665522D03*
X410260Y1390504D03*
X393960Y1375504D03*
X394160Y1390404D03*
X396760Y866504D03*
X388260Y393504D03*
X388360Y312204D03*
X388260Y250004D03*
X388311Y259053D03*
X401204Y194315D03*
X377360Y1831304D03*
X385060Y1649804D03*
X358060Y1583404D03*
X358860Y1537904D03*
X358360Y1555604D03*
X359560Y1546604D03*
X350360Y1541304D03*
X355260Y1458004D03*
X343860Y1432204D03*
X337641Y1386762D03*
X338360Y1394004D03*
X350860Y1403004D03*
X377923Y1318359D03*
X371595Y1325571D03*
X384260Y1363504D03*
X335200Y1273304D03*
X335260Y1278604D03*
X364060Y1300620D03*
X356260Y1193504D03*
Y1202504D03*
X378160Y1102404D03*
X344760Y1068004D03*
X355360Y1068504D03*
X357160Y1063704D03*
X335760Y959004D03*
X348260Y1002504D03*
X354360Y999404D03*
X361260Y1001704D03*
X339760Y982604D03*
X369760Y994404D03*
X384060Y876804D03*
X369160Y835804D03*
X350260Y735904D03*
X361760Y341004D03*
X356860Y362604D03*
X367960Y359304D03*
X358960Y327204D03*
X359760Y252004D03*
X348760Y251504D03*
Y269504D03*
X334760Y254894D03*
Y268394D03*
Y242504D03*
X342260Y202004D03*
X349760Y208504D03*
X348760Y235504D03*
X334260Y194394D03*
X340260Y166504D03*
X348260Y155504D03*
X348760Y138504D03*
X349260Y170504D03*
X334760Y175394D03*
X364260Y163004D03*
X337260Y98904D03*
X345760Y130004D03*
X348260Y121504D03*
X336160Y124004D03*
X335560Y116204D03*
X339260Y53504D03*
X355260Y51504D03*
X302760Y1526504D03*
X298760Y1539504D03*
X296160Y1559604D03*
X306260Y1482404D03*
X314760Y1499004D03*
X305760Y1491804D03*
X324360Y1426904D03*
X321460Y1422904D03*
X300460Y1369804D03*
X309242Y1383604D03*
X314922Y1388008D03*
X302695Y1375658D03*
X326715Y1367307D03*
X319460Y1411104D03*
X286060Y1402104D03*
X324760Y1400904D03*
X321682Y1362733D03*
X328197Y1339370D03*
X329797Y1345361D03*
X292260Y1314904D03*
X299172Y1302592D03*
X301960Y1311904D03*
X309860Y1310004D03*
X296058Y1311004D03*
X315760Y1236504D03*
X325760Y1240504D03*
X303760Y1244004D03*
X312260Y1159004D03*
X301960Y1131504D03*
X328560Y1110404D03*
X328860Y1119604D03*
X317860Y1130204D03*
X322560Y1091404D03*
X328460Y1103204D03*
X310160Y1091804D03*
X313060Y1015004D03*
X308276Y1021669D03*
X301206Y1022904D03*
X290357Y1010326D03*
X287760Y1015504D03*
X326760Y1018004D03*
X310860Y970654D03*
X302180Y975604D03*
X293560Y970104D03*
X333660Y1002604D03*
X330718Y980546D03*
X323302Y1001546D03*
X317760Y1002004D03*
X290360Y965104D03*
X329760Y938004D03*
X292760Y891704D03*
X298398Y583004D03*
X292260Y552079D03*
X321760Y561004D03*
X321260Y525504D03*
X309427Y498837D03*
X320260Y507754D03*
X308236Y516425D03*
X304138Y520503D03*
X304065Y512434D03*
X299922Y516483D03*
X304236Y516504D03*
X285160Y504604D03*
X321060Y534704D03*
X286860Y514204D03*
X321560Y517804D03*
X288260Y520904D03*
X318260Y539004D03*
X298260Y537204D03*
X294285Y533104D03*
X293960Y499704D03*
X303760Y449004D03*
X316927Y470337D03*
X291080Y481824D03*
X284760Y487079D03*
X323260Y403804D03*
X300760Y362504D03*
X331760Y358504D03*
X284760Y317504D03*
X312760Y241504D03*
X322760Y251504D03*
Y272004D03*
X322260Y261504D03*
X311760Y249004D03*
X311260Y259004D03*
X311760Y269504D03*
X301760Y258394D03*
Y271894D03*
Y243394D03*
X309760Y200004D03*
X303760Y236504D03*
X301760Y208504D03*
X323760Y193004D03*
X312992Y191204D03*
X301760Y221394D03*
X283260Y144504D03*
X310760Y167504D03*
X332760Y183504D03*
X323760Y172504D03*
X323260Y182504D03*
X313492Y179394D03*
X301260Y157004D03*
X301760Y172004D03*
X284260Y91004D03*
X307260Y125004D03*
X324260Y118004D03*
X300760Y132004D03*
Y118004D03*
X312760Y116894D03*
X258648Y1530335D03*
X277860Y1560304D03*
X276860Y1497704D03*
X272260Y1446004D03*
X246460Y1436304D03*
X269760Y1435504D03*
X257060Y1426604D03*
X271760Y1393904D03*
X276030Y1396804D03*
X258160Y1363787D03*
X247160Y1315604D03*
X244960Y1359869D03*
X264060Y1347704D03*
X274597Y1334453D03*
X272665Y1350204D03*
X269925Y1328104D03*
X276060Y1323904D03*
X268060Y1315304D03*
X242243Y1348491D03*
X248260Y1277504D03*
X279260Y1267504D03*
X262760Y1273504D03*
X275760Y1293504D03*
X253660Y1265204D03*
X276260Y1256754D03*
X260760Y1052004D03*
X281760Y1017004D03*
X278160Y961404D03*
X259260Y941504D03*
X235260Y835504D03*
X242760Y700004D03*
X261486Y554130D03*
X255760Y517904D03*
X283260Y520004D03*
X278860Y468604D03*
X272760Y489004D03*
X282260Y272004D03*
Y256004D03*
X282760Y241004D03*
X239760Y252004D03*
X262760D03*
X253760Y252504D03*
X239260Y242504D03*
Y264504D03*
X252760Y263504D03*
X262760D03*
X236760Y272004D03*
X258260Y271504D03*
X246992Y271394D03*
X269260D03*
Y257894D03*
Y242894D03*
X236260Y230004D03*
X237660Y203404D03*
X252260Y187004D03*
X258760Y195504D03*
X268760Y197394D03*
X247992Y192504D03*
X282260Y168004D03*
X264760Y186504D03*
X265760Y170004D03*
X254760Y170504D03*
X242260Y170004D03*
X235760Y164004D03*
X235260Y178504D03*
X259260D03*
X248492Y178394D03*
X269260D03*
X282260Y117504D03*
X282760Y129004D03*
X236260Y116004D03*
X259760D03*
X238160Y130204D03*
X248260Y115894D03*
X269760Y117394D03*
X281399Y79043D03*
X231332Y1532704D03*
X223760Y1487004D03*
X232260Y536504D03*
G54D213*
X388760Y1647204D03*
X387760Y884904D03*
X399260Y324204D03*
X399460Y247804D03*
X397660Y275704D03*
X360960Y1813204D03*
Y1805204D03*
Y1789204D03*
Y1809204D03*
Y1793204D03*
X371360Y1755104D03*
X360060Y1751504D03*
X360960Y1769204D03*
X385060Y1696204D03*
X347060Y1537204D03*
X356860Y1391304D03*
X339304Y1278039D03*
X337160Y1282104D03*
X372460Y1052104D03*
X349160Y968704D03*
X368460Y198704D03*
X329557Y1907002D03*
X332060Y1897004D03*
X299960Y1531004D03*
X291904Y1276339D03*
X292004Y1280439D03*
Y1284839D03*
X304960Y1297904D03*
X333864Y1120004D03*
Y1124404D03*
Y1115604D03*
X333860Y1111304D03*
Y1102804D03*
Y1107004D03*
X305960Y560304D03*
X326560Y517504D03*
X308160Y542604D03*
X326560Y529504D03*
X333560Y484504D03*
X289060Y486504D03*
X257960Y1422904D03*
X255160Y1345804D03*
X265531Y1353439D03*
X246060Y1267404D03*
X265764Y549304D03*
Y553504D03*
X277360Y510104D03*
X265760Y545104D03*
X227060Y1529004D03*
G54D214*
X343860Y988454D03*
Y992204D03*
Y995954D03*
X333260D03*
Y992204D03*
Y988454D03*
G54D215*
X353262Y1915401D03*
X353862Y1900901D03*
X360660Y1776904D03*
X358660Y1722704D03*
X360260Y1731904D03*
X359660Y1760604D03*
X366960Y1708604D03*
X362960D03*
X384060Y1715004D03*
X347560Y1428604D03*
X342660Y1397404D03*
X347360Y1413104D03*
X382260Y1390604D03*
X344060Y1266004D03*
X344260Y1241104D03*
X377860Y1075804D03*
X339862Y845801D03*
X357762Y848101D03*
X358062Y829901D03*
X372960Y216204D03*
X284481Y1428833D03*
X304460Y1383308D03*
X292360D03*
X329960Y1398704D03*
X284581Y1414733D03*
X291925Y1309875D03*
X287725D03*
X316360Y1309704D03*
X305660Y1311704D03*
X304960Y1301304D03*
X301660Y1140104D03*
X310060D03*
X318360Y1140108D03*
X299589Y1032148D03*
X303960Y1032204D03*
X310760D03*
X285260Y1024104D03*
X289760D03*
X297960Y970604D03*
X301960D03*
X306460D03*
X322260Y992204D03*
X286260Y968704D03*
X298260Y547704D03*
X293760D03*
X303260D03*
X325660Y548204D03*
X325760Y507704D03*
X284260Y470204D03*
X288260D03*
X292260D03*
X296260D03*
X300260D03*
X304260D03*
X308260D03*
X312260D03*
X327760Y492704D03*
X275960Y1389704D03*
X267760Y1401904D03*
X269925Y1336075D03*
X272825Y1318575D03*
X277025D03*
X266760Y1269204D03*
X253560Y1272304D03*
X262760Y1269204D03*
X272260Y1022704D03*
X268260D03*
X264260D03*
X276260D03*
X280760Y1024104D03*
X282160Y968804D03*
X264629Y540823D03*
X260429Y541623D03*
X268929Y540823D03*
X272760Y497804D03*
X255860Y541704D03*
X270260Y480704D03*
X274760D03*
X279260D03*
X283360Y480804D03*
G54D216*
X351625Y1606604D03*
X310525Y1606704D03*
X280795D03*
X321895Y1606604D03*
X233695Y460804D03*
X263425D03*
G54D15*
X389961Y1737638D03*
Y1747638D03*
Y1757638D03*
Y1619941D03*
Y1629941D03*
Y1609941D03*
Y1064587D03*
Y1044587D03*
Y1054587D03*
Y903917D03*
Y913917D03*
Y923917D03*
Y348563D03*
Y358563D03*
Y338563D03*
Y210866D03*
Y220866D03*
Y230866D03*
G54D217*
X388901Y288004D03*
X360619D03*
G54D218*
X398360Y1570704D03*
Y1550204D03*
X402160Y1301504D03*
X384660Y417004D03*
X340160Y1570004D03*
X373560Y1570704D03*
X340160Y1549504D03*
X373560Y1550204D03*
X377360Y1301504D03*
X347660Y1170104D03*
X357560Y877904D03*
X332760D03*
X359860Y417004D03*
X283360Y1880004D03*
X308160D03*
X315360Y1570004D03*
Y1549504D03*
X322860Y1170104D03*
X235960Y1570604D03*
X260760D03*
X236060Y1611804D03*
X260860D03*
X235860Y1591604D03*
X260660D03*
X235960Y1550104D03*
X260760D03*
X236360Y437004D03*
X261160D03*
X236260Y416904D03*
X261060D03*
G54D219*
X331825Y1325875D03*
Y1333475D03*
X331760Y506804D03*
Y499204D03*
X249160Y1419404D03*
Y1427004D03*
X268995Y1367133D03*
X251160Y1360904D03*
Y1353304D03*
X268995Y1359533D03*
X254260Y510804D03*
Y503204D03*
G54D220*
X351058Y830157D03*
Y843457D03*
X379660Y200954D03*
Y214254D03*
X332758Y832257D03*
Y845557D03*
G54D221*
X399910Y187504D03*
X386610D03*
X343307Y1914002D03*
X349610Y1384504D03*
X362910D03*
X376210Y1375504D03*
X362910D03*
X339410Y1253104D03*
X339910Y1228104D03*
X361110Y956704D03*
X347810D03*
X356810Y936404D03*
X343510D03*
X330007Y1914002D03*
X325410Y1900004D03*
X312110D03*
X326110Y1253104D03*
X326610Y1228104D03*
G54D222*
X393360Y1721604D03*
X395960Y1640004D03*
X384960D03*
X405060Y311404D03*
X394060D03*
X405460Y269304D03*
X394460D03*
X382360Y1721604D03*
X296564Y576204D03*
X285564D03*
X315260Y581004D03*
X304260D03*
X267260D03*
X278260D03*
G54D223*
X352260Y1528504D03*
X347260D03*
X342260D03*
X337260D03*
X360860Y392904D03*
X355860D03*
X350860D03*
X345860D03*
X324760Y1529004D03*
X319760D03*
X314760D03*
X309760D03*
X292760Y393004D03*
X287760D03*
X327760D03*
X322760D03*
X317760D03*
X312760D03*
X280260Y1529004D03*
X275260D03*
X270260D03*
X265260D03*
X252260D03*
X247260D03*
X242260D03*
X237260D03*
X258760Y393004D03*
X253760D03*
X248760D03*
X243760D03*
X282760D03*
X277760D03*
G54D224*
X349458Y1911957D03*
X349860Y1896750D03*
X346060Y1227004D03*
X345560Y1249404D03*
X367460Y955404D03*
X317760Y1371004D03*
X274895Y1357183D03*
G54D225*
X386860Y1674204D03*
X343013Y1907106D03*
X370660Y1715704D03*
X335331Y1434825D03*
X353360Y1377504D03*
X350260Y981904D03*
X359260Y943504D03*
X309960Y1588404D03*
X319760Y982504D03*
Y977704D03*
X332060Y513004D03*
X320060Y494004D03*
X260960Y1436404D03*
X261160Y1415204D03*
X244839Y1354969D03*
X266560Y506004D03*
G54D226*
X341060Y491004D03*
X313660Y1410204D03*
X306060D03*
X333460Y491004D03*
X314490Y487864D03*
X322090D03*
X237560Y362004D03*
X240560Y327504D03*
X232960D03*
X229960Y362004D03*
G54D202*
X271260Y1904004D03*
X268760Y62504D03*
G54D227*
X328054Y1291089D03*
Y1286089D03*
Y1281089D03*
Y1276089D03*
X307954D03*
Y1281089D03*
Y1286089D03*
Y1291089D03*
G54D228*
X349260Y1494956D03*
Y1477052D03*
X331260Y1494956D03*
Y1477052D03*
X245260Y1495456D03*
Y1477552D03*
X263260Y1495456D03*
Y1477552D03*
G54D229*
X387860Y1397704D03*
X393560Y862504D03*
X399260Y328304D03*
X387160Y194104D03*
X397960Y198904D03*
X350560Y1905004D03*
X360960Y1797204D03*
Y1785204D03*
Y1801204D03*
Y1781204D03*
X360060Y1747504D03*
X371360Y1751104D03*
X385178Y1704287D03*
X360960Y1688504D03*
X339316Y1273869D03*
X337860Y1286304D03*
X352560Y1238504D03*
X349160Y964204D03*
X358260Y947904D03*
X345560Y943104D03*
X345460Y947604D03*
X379860Y872504D03*
X349060Y793404D03*
X382860Y180304D03*
X319160Y1418904D03*
X334160Y1398604D03*
X326560Y1297504D03*
X302260Y1308304D03*
X312960Y1306304D03*
X330060Y1260604D03*
X331560Y1235104D03*
X308160Y546904D03*
X313760Y560404D03*
X288060Y540204D03*
X326560Y522004D03*
X267760Y1537704D03*
X272560Y1400504D03*
X265060Y1381504D03*
X255160Y1341804D03*
X243560Y1344204D03*
X269856Y574504D03*
X277360Y502104D03*
Y506104D03*
X277660Y515204D03*
X260560Y510504D03*
G54D230*
X387660Y198604D03*
X339960Y1897004D03*
X357460Y1306204D03*
Y1310904D03*
X366960Y203804D03*
X305460Y1199404D03*
Y1204404D03*
X315960Y910104D03*
Y914804D03*
X233360Y315804D03*
Y320504D03*
X273813Y89806D03*
X273860Y84804D03*
G54D231*
X349458Y1915557D03*
X349860Y1900350D03*
X346060Y1230604D03*
X345560Y1253004D03*
X367460Y959004D03*
X317760Y1374604D03*
X274895Y1360783D03*
G54D232*
X386260Y1387204D03*
X363160Y937704D03*
X333860Y1394404D03*
X271760Y1389904D03*
X256660Y1360004D03*
X270760Y1269304D03*
G54D233*
X342360Y469804D03*
Y445004D03*
X296962Y85001D03*
Y60201D03*
X275462Y817201D03*
Y842001D03*
G54D234*
X249890Y1333685D03*
X261460D03*
X249890Y1322665D03*
X261460D03*
G54D17*
X374016Y1900394D03*
Y1467166D03*
Y1207323D03*
Y761181D03*
Y501339D03*
Y68111D03*
G54D235*
X286551Y1258004D03*
X303969D03*
G54D236*
X335860Y1423754D03*
X337830D03*
X339795D03*
Y1407454D03*
X337830D03*
X335860D03*
X331925Y1423754D03*
X333890D03*
Y1407454D03*
X331925D03*
X312550Y1355875D03*
X310585D03*
X308615D03*
X306645D03*
X304680D03*
X302710D03*
X300740D03*
X298770D03*
X296805D03*
X294835D03*
X292865D03*
X290900D03*
Y1322475D03*
X292865D03*
X294835D03*
X296805D03*
X298770D03*
X300740D03*
X302710D03*
X304680D03*
X306645D03*
X308615D03*
X310585D03*
X312550D03*
X268125Y1425554D03*
X270090D03*
X272060D03*
X274030D03*
X275995D03*
Y1409254D03*
X274030D03*
X272060D03*
X270090D03*
X268125D03*
G54D237*
X393260Y198604D03*
X345560Y1897004D03*
X363060Y1306204D03*
Y1310904D03*
X372560Y203804D03*
X311060Y1199404D03*
Y1204404D03*
X321560Y910104D03*
Y914804D03*
X238960Y315804D03*
Y320504D03*
X279413Y89806D03*
X279460Y84804D03*
G54D238*
X388578Y1704287D03*
X391260Y1397704D03*
X396960Y862504D03*
X402660Y328304D03*
X390560Y194104D03*
X401360Y198904D03*
X386260Y180304D03*
X353960Y1905004D03*
X364360Y1797204D03*
Y1785204D03*
Y1801204D03*
Y1781204D03*
X363460Y1747504D03*
X374760Y1751104D03*
X364360Y1688504D03*
X337560Y1398604D03*
X342716Y1273869D03*
X341260Y1286304D03*
X334960Y1235104D03*
X355960Y1238504D03*
X352560Y964204D03*
X361660Y947904D03*
X348960Y943104D03*
X348860Y947604D03*
X383260Y872504D03*
X352460Y793404D03*
X322560Y1418904D03*
X329960Y1297504D03*
X305660Y1308304D03*
X316360Y1306304D03*
X333460Y1260604D03*
X311560Y546904D03*
X317160Y560404D03*
X291460Y540204D03*
X329960Y522004D03*
X271160Y1537704D03*
X275960Y1400504D03*
X268460Y1381504D03*
X258560Y1341804D03*
X246960Y1344204D03*
X273256Y574504D03*
X280760Y502104D03*
Y506104D03*
X281060Y515204D03*
X263960Y510504D03*
G54D239*
X390960Y180704D03*
X356760Y1395504D03*
X339360Y1002304D03*
X350060Y824004D03*
X334260Y825504D03*
X326460Y537004D03*
Y533604D03*
X287960Y536504D03*
X326460Y525704D03*
X257860Y1419204D03*
X276960Y1273004D03*
G54D240*
X388560Y1715004D03*
X401977Y1661222D03*
X388360Y307704D03*
X395360Y246804D03*
X364660Y1776904D03*
X363860Y1760604D03*
X364360Y1731904D03*
X358260Y1704204D03*
X382060Y1624704D03*
X339860Y1438004D03*
X342860Y1380904D03*
X371660Y1395004D03*
X359860Y1295104D03*
X363860D03*
X357160Y1059104D03*
X344258Y834007D03*
X337760Y506704D03*
X325160Y1438004D03*
X296360Y1383300D03*
X300460D03*
X328195Y1374433D03*
X323995D03*
X328795Y1361533D03*
X326060Y1306204D03*
X310360Y1087104D03*
X318660D03*
X301960D03*
X298731Y1016160D03*
X303731D03*
X308731D03*
X320760Y548204D03*
X329760D03*
X316260D03*
X286260Y560100D03*
X286560Y567900D03*
X313760Y481704D03*
X250660Y1439404D03*
X265660Y1439504D03*
X263260Y1393304D03*
X251060Y1344804D03*
X240895Y1326133D03*
X283495Y1309833D03*
X266760Y1284704D03*
X271760Y1260204D03*
X273360Y968804D03*
X269160Y968704D03*
X257760Y974204D03*
X261760D03*
X277460Y968704D03*
X283760Y528204D03*
G54D241*
X386260Y1383604D03*
X363160Y934104D03*
X333860Y1390804D03*
X271760Y1386304D03*
X256660Y1356404D03*
X270760Y1265704D03*
G54D242*
X350010Y355207D03*
Y348801D03*
X291010Y355207D03*
Y348801D03*
X319510Y355207D03*
Y348801D03*
X263510Y355207D03*
Y348801D03*
G54D18*
X340551Y1849095D03*
Y1639095D03*
X271654Y1849095D03*
Y1639095D03*
G54D243*
X305085Y1122200D03*
X307640D03*
X310200D03*
X312760D03*
X315320D03*
X317880D03*
X320435D03*
Y1100000D03*
X317880D03*
X315320D03*
X312760D03*
X310200D03*
X307640D03*
X305085D03*
X299620Y1005504D03*
X302180D03*
X304740D03*
X307300D03*
Y983304D03*
X304740D03*
X302180D03*
X299620D03*
X265435Y1236200D03*
X262880D03*
X260320D03*
X257760D03*
X255200D03*
X252640D03*
X250085D03*
Y1258400D03*
X252640D03*
X255200D03*
X257760D03*
X260320D03*
X262880D03*
X265435D03*
X283920Y1009004D03*
X281360D03*
X278800D03*
X276240D03*
X273680D03*
X271120D03*
X268560D03*
X266000D03*
Y986804D03*
X268560D03*
X271120D03*
X273680D03*
X276240D03*
X278800D03*
X281360D03*
X283920D03*
G54D244*
X240795Y1337133D03*
Y1333533D03*
G54D71*
X347360Y1418404D03*
X284489Y1419983D03*
X288525Y1375075D03*
X295425Y1374875D03*
X289325Y1366575D03*
X316260Y1365304D03*
X319360Y1314404D03*
X328289Y1351169D03*
X304160Y538404D03*
X276931Y1369739D03*
X281331Y1364339D03*
X281125Y1375275D03*
X260560Y1352604D03*
X270231Y1340939D03*
X264560Y1341704D03*
X242260Y1262004D03*
X273660Y973904D03*
X267260Y974004D03*
X279260D03*
G54D245*
X324803Y195079D03*
G54D246*
X394560Y180704D03*
X360360Y1395504D03*
X342960Y1002304D03*
X337860Y825504D03*
X353660Y824004D03*
X330060Y537004D03*
Y533604D03*
X291560Y536504D03*
X330060Y525704D03*
X261460Y1419204D03*
X280560Y1273004D03*
G54D247*
X385010Y1277944D03*
Y1280504D03*
Y1283064D03*
X369510Y1277944D03*
Y1280504D03*
Y1283064D03*
X363010D03*
Y1277944D03*
X378510Y1283064D03*
Y1277944D03*
G54D248*
X280160Y566808D03*
Y558408D03*
X262660Y522100D03*
Y530500D03*
G54D249*
X307460Y571364D03*
Y568804D03*
Y566244D03*
X314860D03*
Y568804D03*
Y571364D03*
G54D19*
X340551Y1829095D03*
Y1659095D03*
X271654Y1829095D03*
Y1659095D03*
G54D250*
X347857Y1361802D03*
Y1335002D03*
X299163Y843206D03*
Y816406D03*
X322763Y85306D03*
Y58506D03*
G54D251*
X273760Y531254D03*
X277635Y523754D03*
X269885D03*
G54D252*
X354385Y1293898D03*
X351825D03*
X349265D03*
Y1287398D03*
X354385D03*
G54D253*
X373060Y208204D03*
X322660Y1415204D03*
X334460Y1430704D03*
X325160D03*
X308360Y1365004D03*
X313660Y1374804D03*
X250660Y1432104D03*
X260360Y1432004D03*
G54D254*
X296260Y559050D03*
X300135Y566550D03*
X292385D03*
G54D255*
X349060Y1882304D03*
X348658Y1210607D03*
X357560Y918404D03*
X322260Y1882304D03*
X321858Y1210607D03*
X330760Y918404D03*
G54D20*
X340551Y1806615D03*
Y1796615D03*
Y1786615D03*
Y1776615D03*
Y1764095D03*
Y1754095D03*
Y1744095D03*
Y1734095D03*
Y1724095D03*
Y1711575D03*
Y1701575D03*
Y1691575D03*
Y1681575D03*
X310551Y1806615D03*
Y1796615D03*
X320551Y1806615D03*
Y1796615D03*
X330551Y1806615D03*
Y1796615D03*
X310551Y1786615D03*
Y1776615D03*
X320551Y1786615D03*
Y1776615D03*
X330551Y1786615D03*
Y1776615D03*
X310551Y1764095D03*
Y1754095D03*
Y1744095D03*
Y1734095D03*
Y1724095D03*
X320551Y1764095D03*
Y1754095D03*
Y1744095D03*
Y1734095D03*
Y1724095D03*
X330551Y1764095D03*
Y1754095D03*
Y1744095D03*
Y1734095D03*
Y1724095D03*
X310551Y1711575D03*
Y1701575D03*
X320551Y1711575D03*
Y1701575D03*
X330551Y1711575D03*
Y1701575D03*
X310551Y1691575D03*
Y1681575D03*
X320551Y1691575D03*
Y1681575D03*
X330551Y1691575D03*
Y1681575D03*
X241654Y1806615D03*
Y1796615D03*
X251654Y1806615D03*
Y1796615D03*
X261654Y1806615D03*
Y1796615D03*
X271654Y1806615D03*
Y1796615D03*
X241654Y1786615D03*
Y1776615D03*
X251654Y1786615D03*
Y1776615D03*
X261654Y1786615D03*
Y1776615D03*
X271654Y1786615D03*
Y1776615D03*
X241654Y1764095D03*
Y1754095D03*
Y1744095D03*
Y1734095D03*
Y1724095D03*
X251654Y1764095D03*
Y1754095D03*
Y1744095D03*
Y1734095D03*
Y1724095D03*
X261654Y1764095D03*
Y1754095D03*
Y1744095D03*
Y1734095D03*
Y1724095D03*
X271654Y1764095D03*
Y1754095D03*
Y1744095D03*
Y1734095D03*
Y1724095D03*
X241654Y1711575D03*
Y1701575D03*
X251654Y1711575D03*
Y1701575D03*
X261654Y1711575D03*
Y1701575D03*
X271654Y1711575D03*
Y1701575D03*
X241654Y1691575D03*
Y1681575D03*
X251654Y1691575D03*
Y1681575D03*
X261654Y1691575D03*
Y1681575D03*
X271654Y1691575D03*
Y1681575D03*
G54D256*
X371360Y1084704D03*
Y1073704D03*
X357460Y981904D03*
Y992904D03*
X382260Y946004D03*
Y935004D03*
X325260Y1037504D03*
Y1026504D03*
X274260Y1236504D03*
Y1247504D03*
G54D257*
X309378Y506904D03*
X306819D03*
X304260D03*
X301701D03*
X299142D03*
Y526104D03*
X301701D03*
X304260D03*
X306819D03*
X309378D03*
G54D258*
X278960Y496704D03*
Y487704D03*
G54D259*
X373762Y1729605D03*
X369060Y1729604D03*
X358560Y1714304D03*
X376160Y1391204D03*
X339760Y1240904D03*
X358058Y840157D03*
X317360Y1491904D03*
X324960Y1410804D03*
X292195Y1295410D03*
X297795D03*
X296360Y1245904D03*
X326760Y991804D03*
X290460Y992704D03*
X287760Y497304D03*
X274560Y1491804D03*
X257960Y1272004D03*
X276960Y857204D03*
X272258Y857157D03*
G54D260*
X369460Y208204D03*
X319060Y1415204D03*
X330860Y1430704D03*
X321560D03*
X304760Y1365004D03*
X310060Y1374804D03*
X247060Y1432104D03*
X256760Y1432004D03*
G54D261*
X334561Y1018904D03*
X357359D03*
G54D21*
X324803Y220669D03*
Y145473D03*
X242323Y639764D03*
X259843Y220669D03*
Y145473D03*
G54D262*
X294660Y511386D03*
Y513945D03*
Y516504D03*
Y519063D03*
Y521622D03*
X313860D03*
Y519063D03*
Y516504D03*
Y513945D03*
Y511386D03*
G54D263*
X304260Y516504D03*
G54D264*
X285025Y1350000D03*
Y1348035D03*
Y1346065D03*
Y1344095D03*
Y1342130D03*
Y1340160D03*
Y1338190D03*
Y1336220D03*
Y1334255D03*
Y1332285D03*
Y1330315D03*
Y1328350D03*
X318425D03*
Y1330315D03*
Y1332285D03*
Y1334255D03*
Y1336220D03*
Y1338190D03*
Y1340160D03*
Y1342130D03*
Y1344095D03*
Y1346065D03*
Y1348035D03*
Y1350000D03*
G54D265*
X259843Y195079D03*
G54D23*
X-448201Y-66763D02*
G01X-480201D01*
X-448201Y-82763D02*
G01Y-162763D01*
Y-118263D02*
G01X752899D01*
X-448201Y-162763D02*
G01X752899D01*
X-452201Y-66763D02*
G75*
G03X-452201Y-66763I-12000D01*
X-457351D02*
G03X-457351Y-66763I-6850D01*
X-464201Y-82763D02*
G01Y-50763D01*
X-448201Y-82763D02*
G01X752899D01*
X-34601D02*
G01Y-162763D01*
X102899Y-82763D02*
G01Y-162763D01*
X217899Y-82763D02*
G01Y-162763D01*
X385399Y-82763D02*
G01Y-162763D01*
X555399Y-82763D02*
G01Y-162763D01*
X752899Y-82763D02*
G01Y-162763D01*
X780899Y-66763D02*
G03X780899Y-66763I-12000D01*
X775749D02*
G03X775749Y-66763I-6850D01*
X768899Y-82763D02*
G01Y-50763D01*
X784899Y-66763D02*
G01X752899D01*
G54D24*
X-430254Y-152763D02*
G01Y-135263D01*
X-421958D02*
G01X-430254Y-146055D01*
X-420648Y-152763D02*
G01X-426543Y-141097D01*
X-412973Y-152763D02*
G01Y-135263D01*
X-402929Y-152763*
Y-135263*
X-390451Y-152763D02*
G01X-392198Y-152471D01*
X-393726Y-151305*
X-395036Y-149555*
X-395910Y-147513*
X-396346Y-145180*
Y-142846*
X-395910Y-140513*
X-395036Y-138471*
X-393726Y-136722*
X-392198Y-135555*
X-390451Y-135263*
X-388705Y-135555*
X-387176Y-136722*
X-385866Y-138471*
X-384992Y-140513*
X-384556Y-142846*
Y-145180*
X-384992Y-147513*
X-385866Y-149555*
X-387176Y-151305*
X-388705Y-152471*
X-390451Y-152763*
X-377536D02*
G01X-368366Y-135263D01*
X-377536D02*
G01X-368366Y-152763D01*
X-362001Y-158596D02*
G01X-348901D01*
X-342099Y-152763D02*
G01Y-135263D01*
X-333803*
X-336859Y-143721D02*
G01X-342099D01*
X-325910Y-152763D02*
G01X-320451Y-135263D01*
X-314992Y-152763*
X-316958Y-146638D02*
G01X-323945D01*
X-307973Y-152763D02*
G01Y-135263D01*
X-297929Y-152763*
Y-135263*
X-263148Y-136722D02*
G01X-264458Y-135846D01*
X-265986Y-135263*
X-267733*
X-269698Y-136138*
X-271226Y-137596*
X-272318Y-139347*
X-273191Y-142263*
X-273410Y-144888*
X-272973Y-147513*
X-272318Y-149263*
X-271008Y-151013*
X-269479Y-152180*
X-267951Y-152763*
X-266423*
X-264894Y-152180*
X-263584Y-151305*
X-262492Y-150139*
X-250451Y-152763D02*
G01X-252198Y-152471D01*
X-253726Y-151305*
X-255036Y-149555*
X-255910Y-147513*
X-256346Y-145180*
Y-142846*
X-255910Y-140513*
X-255036Y-138471*
X-253726Y-136722*
X-252198Y-135555*
X-250451Y-135263*
X-248705Y-135555*
X-247176Y-136722*
X-245866Y-138471*
X-244992Y-140513*
X-244556Y-142846*
Y-145180*
X-244992Y-147513*
X-245866Y-149555*
X-247176Y-151305*
X-248705Y-152471*
X-250451Y-152763*
X-237973D02*
G01Y-135263D01*
X-227929Y-152763*
Y-135263*
X-215451D02*
G01Y-152763D01*
X-220473Y-135263D02*
G01X-210429D01*
X-202318Y-152763D02*
G01Y-135263D01*
X-196859*
X-195113Y-136138*
X-194021Y-137305*
X-193584Y-139638*
X-194021Y-141972*
X-195331Y-143430*
X-196859Y-144305*
X-202318*
X-196859D02*
G01X-193584Y-152763D01*
X-180451D02*
G01X-182198Y-152471D01*
X-183726Y-151305*
X-185036Y-149555*
X-185910Y-147513*
X-186346Y-145180*
Y-142846*
X-185910Y-140513*
X-185036Y-138471*
X-183726Y-136722*
X-182198Y-135555*
X-180451Y-135263*
X-178705Y-135555*
X-177176Y-136722*
X-175866Y-138471*
X-174992Y-140513*
X-174556Y-142846*
Y-145180*
X-174992Y-147513*
X-175866Y-149555*
X-177176Y-151305*
X-178705Y-152471*
X-180451Y-152763*
X-167318Y-135263D02*
G01Y-152763D01*
X-158584*
X-126205Y-143430D02*
G01X-125331Y-142555D01*
X-124676Y-141097*
X-124239Y-139054*
X-124676Y-137305*
X-125549Y-136138*
X-127078Y-135263*
X-132973*
Y-152763*
X-125768*
X-124239Y-151597*
X-123366Y-149846*
X-122929Y-147805*
X-123366Y-145763*
X-124676Y-144013*
X-126205Y-143430*
X-132973*
X-110451Y-152763D02*
G01X-112198Y-152471D01*
X-113726Y-151305*
X-115036Y-149555*
X-115910Y-147513*
X-116346Y-145180*
Y-142846*
X-115910Y-140513*
X-115036Y-138471*
X-113726Y-136722*
X-112198Y-135555*
X-110451Y-135263*
X-108705Y-135555*
X-107176Y-136722*
X-105866Y-138471*
X-104992Y-140513*
X-104556Y-142846*
Y-145180*
X-104992Y-147513*
X-105866Y-149555*
X-107176Y-151305*
X-108705Y-152471*
X-110451Y-152763*
X-98410D02*
G01X-92951Y-135263D01*
X-87492Y-152763*
X-89458Y-146638D02*
G01X-96445D01*
X-79818Y-152763D02*
G01Y-135263D01*
X-74359*
X-72613Y-136138*
X-71521Y-137305*
X-71084Y-139638*
X-71521Y-141972*
X-72831Y-143430*
X-74359Y-144305*
X-79818*
X-74359D02*
G01X-71084Y-152763D01*
X-62754D02*
G01Y-135263D01*
X-58388*
X-56641Y-136138*
X-55331Y-137305*
X-54239Y-139054*
X-53366Y-141097*
X-53148Y-144013*
X-53366Y-146930*
X-54239Y-148972*
X-55331Y-150722*
X-56641Y-151888*
X-58388Y-152763*
X-62754*
X-282378Y-107763D02*
G01Y-90263D01*
X-276701Y-104846*
X-271024Y-90263*
Y-107763*
X-259201D02*
G01X-260511Y-107471D01*
X-261821Y-106305*
X-262695Y-104263*
X-263131Y-101930*
X-262695Y-99596*
X-261821Y-97555*
X-260511Y-96388*
X-259201Y-96097*
X-257891Y-96388*
X-256581Y-97555*
X-255708Y-99596*
X-255489Y-101930*
X-255708Y-104263*
X-256581Y-106305*
X-257891Y-107471*
X-259201Y-107763*
X-237771Y-90263D02*
G01Y-107763D01*
Y-105139D02*
G01X-238644Y-106597D01*
X-239955Y-107471*
X-241483Y-107763*
X-243229Y-107180*
X-244539Y-105722*
X-245413Y-103972*
X-245631Y-101930*
X-245413Y-99888*
X-244539Y-98138*
X-243229Y-96680*
X-241483Y-96097*
X-239955Y-96388*
X-238863Y-96972*
X-237771Y-98138*
X-227476Y-99888D02*
G01X-220489D01*
X-221144Y-97846*
X-222236Y-96680*
X-223764Y-96097*
X-225293Y-96388*
X-226603Y-97263*
X-227476Y-99305*
X-227913Y-101055*
Y-102805*
X-227476Y-104555*
X-226384Y-106305*
X-225074Y-107471*
X-223546Y-107763*
X-222018Y-107180*
X-220489Y-105430*
X-206701Y-107763D02*
G01Y-90263D01*
X-14018Y-107763D02*
G01Y-90263D01*
X-8778*
X-7031Y-91138*
X-5721Y-93180*
X-5284Y-95513*
X-5721Y-97846*
X-6813Y-99596*
X-8778Y-100472*
X-14018*
X12652Y-91722D02*
G01X11342Y-90846D01*
X9814Y-90263*
X8067*
X6102Y-91138*
X4574Y-92596*
X3482Y-94347*
X2609Y-97263*
X2390Y-99888*
X2827Y-102513*
X3482Y-104263*
X4792Y-106013*
X6321Y-107180*
X7849Y-107763*
X9377*
X10906Y-107180*
X12216Y-106305*
X13308Y-105139*
X27095Y-98430D02*
G01X27969Y-97555D01*
X28624Y-96097*
X29061Y-94054*
X28624Y-92305*
X27751Y-91138*
X26222Y-90263*
X20327*
Y-107763*
X27532*
X29061Y-106597*
X29934Y-104846*
X30371Y-102805*
X29934Y-100763*
X28624Y-99013*
X27095Y-98430*
X20327*
X36299Y-113596D02*
G01X49399D01*
X55327Y-107763D02*
G01Y-90263D01*
X65371Y-107763*
Y-90263*
X77849Y-107763D02*
G01X76102Y-107471D01*
X74574Y-106305*
X73264Y-104555*
X72390Y-102513*
X71954Y-100180*
Y-97846*
X72390Y-95513*
X73264Y-93471*
X74574Y-91722*
X76102Y-90555*
X77849Y-90263*
X79595Y-90555*
X81124Y-91722*
X82434Y-93471*
X83308Y-95513*
X83744Y-97846*
Y-100180*
X83308Y-102513*
X82434Y-104555*
X81124Y-106305*
X79595Y-107471*
X77849Y-107763*
X-901Y-152763D02*
G01Y-135263D01*
X-3521Y-138763*
Y-152763D02*
G01X1719D01*
X12451Y-138180D02*
G01X13761Y-136430D01*
X15289Y-135555*
X17036Y-135263*
X19219Y-135846*
X20747Y-137305*
X21184Y-139054*
X20966Y-140805*
X20092Y-142263*
X15726Y-145180*
X13761Y-147221*
X12451Y-150139*
X12014Y-152763*
X21184*
X36719D02*
G01Y-135263D01*
X28640Y-147805*
X39558*
X46796Y-149263D02*
G01X48105Y-151305D01*
X49852Y-152471*
X51817Y-152763*
X53564Y-152471*
X55311Y-151013*
X56402Y-149263*
X56621Y-147513*
X56184Y-145472*
X54656Y-144013*
X53127Y-143430*
X51162*
X53127D02*
G01X54437Y-142555D01*
X55529Y-141097*
X55966Y-139347*
X55529Y-137596*
X54437Y-136138*
X52472Y-135263*
X50507Y-135555*
X48542Y-136722*
X64296Y-149263D02*
G01X65605Y-151305D01*
X67352Y-152471*
X69317Y-152763*
X71064Y-152471*
X72811Y-151013*
X73902Y-149263*
X74121Y-147513*
X73684Y-145472*
X72156Y-144013*
X70627Y-143430*
X68662*
X70627D02*
G01X71937Y-142555D01*
X73029Y-141097*
X73466Y-139347*
X73029Y-137596*
X71937Y-136138*
X69972Y-135263*
X68007Y-135555*
X66042Y-136722*
X128690Y-90263D02*
G01X134149Y-107763D01*
X139608Y-90263*
X156016Y-107763D02*
G01X147282D01*
Y-90263*
X156016*
X152522Y-98721D02*
G01X147282D01*
X164782Y-107763D02*
G01Y-90263D01*
X170241*
X171987Y-91138*
X173079Y-92305*
X173516Y-94638*
X173079Y-96972*
X171769Y-98430*
X170241Y-99305*
X164782*
X170241D02*
G01X173516Y-107763D01*
X186649Y-108346D02*
G01X186212Y-108055D01*
Y-107471*
X186649Y-107180*
X187086Y-107471*
Y-108055*
X186649Y-108346*
X147501Y-138180D02*
G01X148811Y-136430D01*
X150339Y-135555*
X152086Y-135263*
X154269Y-135846*
X155797Y-137305*
X156234Y-139054*
X156016Y-140805*
X155142Y-142263*
X150776Y-145180*
X148811Y-147221*
X147501Y-150139*
X147064Y-152763*
X156234*
X163690D02*
G01X169149Y-135263D01*
X174608Y-152763*
X172642Y-146638D02*
G01X165655D01*
X253482Y-90263D02*
G01Y-107763D01*
X262216*
X279279D02*
G01Y-96097D01*
Y-98138D02*
G01X278406Y-96972D01*
X277095Y-96388*
X275567Y-96097*
X274039Y-96680*
X272729Y-97846*
X271855Y-99596*
X271419Y-101930*
X271855Y-104263*
X272729Y-106013*
X274039Y-107180*
X275567Y-107763*
X277095Y-107471*
X278406Y-106597*
X279279Y-105430*
X288264Y-113013D02*
G01X289574Y-113596D01*
X291321Y-113013*
X292412Y-111847*
X293286Y-110388*
X294595Y-105722*
X297434Y-96097*
X290447D02*
G01X294595Y-105722D01*
X307074Y-99888D02*
G01X314061D01*
X313406Y-97846*
X312314Y-96680*
X310786Y-96097*
X309257Y-96388*
X307947Y-97263*
X307074Y-99305*
X306637Y-101055*
Y-102805*
X307074Y-104555*
X308166Y-106305*
X309476Y-107471*
X311004Y-107763*
X312532Y-107180*
X314061Y-105430*
X324792Y-107763D02*
G01Y-96097D01*
Y-98430D02*
G01X325884Y-97263D01*
X326976Y-96388*
X328504Y-96097*
X329595Y-96388*
X330906Y-97263*
X342074Y-105722D02*
G01X343166Y-106888D01*
X344694Y-107763*
X346004*
X347314Y-107180*
X348187Y-106305*
X348624Y-105139*
X348406Y-103388*
X347532Y-102513*
X343602Y-100763*
X342729Y-98721*
X343166Y-97263*
X344039Y-96388*
X345349Y-96097*
X346659Y-96388*
X347969Y-97263*
X266599Y-135263D02*
G01Y-152763D01*
X261577Y-135263D02*
G01X271621D01*
X278422Y-152763D02*
G01Y-135263D01*
X284099Y-149846*
X289776Y-135263*
Y-152763*
X296140D02*
G01X301599Y-135263D01*
X307058Y-152763*
X305092Y-146638D02*
G01X298105D01*
X314514Y-150430D02*
G01X316261Y-151888D01*
X318226Y-152763*
X319972*
X321719Y-151888*
X323029Y-150430*
X323684Y-148388*
X323247Y-146347*
X322156Y-144596*
X320191Y-143430*
X317571Y-142846*
X316042Y-141680*
X315387Y-139638*
X315824Y-137596*
X316916Y-136138*
X318444Y-135263*
X319972*
X321501Y-135846*
X322811Y-137305*
X331796Y-152763D02*
G01Y-135263D01*
X340092D02*
G01X331796Y-146055D01*
X341402Y-152763D02*
G01X335507Y-141097D01*
X404346Y-107763D02*
G01Y-90263D01*
X408712*
X410459Y-91138*
X411769Y-92305*
X412861Y-94054*
X413734Y-96097*
X413952Y-99013*
X413734Y-101930*
X412861Y-103972*
X411769Y-105722*
X410459Y-106888*
X408712Y-107763*
X404346*
X423374Y-99888D02*
G01X430361D01*
X429706Y-97846*
X428614Y-96680*
X427086Y-96097*
X425557Y-96388*
X424247Y-97263*
X423374Y-99305*
X422937Y-101055*
Y-102805*
X423374Y-104555*
X424466Y-106305*
X425776Y-107471*
X427304Y-107763*
X428832Y-107180*
X430361Y-105430*
X440874Y-105722D02*
G01X441966Y-106888D01*
X443494Y-107763*
X444804*
X446114Y-107180*
X446987Y-106305*
X447424Y-105139*
X447206Y-103388*
X446332Y-102513*
X442402Y-100763*
X441529Y-98721*
X441966Y-97263*
X442839Y-96388*
X444149Y-96097*
X445459Y-96388*
X446769Y-97263*
X461649Y-96097D02*
G01Y-107763D01*
Y-91430D02*
G01X461212Y-91138D01*
Y-90555*
X461649Y-90263*
X462086Y-90555*
Y-91138*
X461649Y-91430*
X476092Y-112138D02*
G01X477621Y-113305D01*
X479367Y-113596*
X480895Y-113305*
X482206Y-111847*
X483079Y-109805*
Y-96097*
Y-98430D02*
G01X482206Y-97263D01*
X480895Y-96388*
X479367Y-96097*
X477621Y-96680*
X476529Y-97846*
X475655Y-99888*
X475219Y-101930*
X475437Y-103680*
X476311Y-105722*
X477621Y-107180*
X479367Y-107763*
X480677Y-107471*
X482206Y-106305*
X483079Y-105139*
X492937Y-107763D02*
G01Y-96097D01*
Y-99013D02*
G01X493811Y-97555D01*
X495121Y-96388*
X496867Y-96097*
X498395Y-96388*
X499706Y-97555*
X500361Y-99596*
Y-107763*
X510874Y-99888D02*
G01X517861D01*
X517206Y-97846*
X516114Y-96680*
X514586Y-96097*
X513057Y-96388*
X511747Y-97263*
X510874Y-99305*
X510437Y-101055*
Y-102805*
X510874Y-104555*
X511966Y-106305*
X513276Y-107471*
X514804Y-107763*
X516332Y-107180*
X517861Y-105430*
X528592Y-107763D02*
G01Y-96097D01*
Y-98430D02*
G01X529684Y-97263D01*
X530776Y-96388*
X532304Y-96097*
X533395Y-96388*
X534706Y-97263*
X429722Y-152763D02*
G01Y-135263D01*
X435399Y-149846*
X441076Y-135263*
Y-152763*
X452899D02*
G01X451152Y-152471D01*
X449624Y-151305*
X448314Y-149555*
X447440Y-147513*
X447004Y-145180*
Y-142846*
X447440Y-140513*
X448314Y-138471*
X449624Y-136722*
X451152Y-135555*
X452899Y-135263*
X454645Y-135555*
X456174Y-136722*
X457484Y-138471*
X458358Y-140513*
X458794Y-142846*
Y-145180*
X458358Y-147513*
X457484Y-149555*
X456174Y-151305*
X454645Y-152471*
X452899Y-152763*
X465814Y-150430D02*
G01X467561Y-151888D01*
X469526Y-152763*
X471272*
X473019Y-151888*
X474329Y-150430*
X474984Y-148388*
X474547Y-146347*
X473456Y-144596*
X471491Y-143430*
X468871Y-142846*
X467342Y-141680*
X466687Y-139638*
X467124Y-137596*
X468216Y-136138*
X469744Y-135263*
X471272*
X472801Y-135846*
X474111Y-137305*
X483314Y-150430D02*
G01X485061Y-151888D01*
X487026Y-152763*
X488772*
X490519Y-151888*
X491829Y-150430*
X492484Y-148388*
X492047Y-146347*
X490956Y-144596*
X488991Y-143430*
X486371Y-142846*
X484842Y-141680*
X484187Y-139638*
X484624Y-137596*
X485716Y-136138*
X487244Y-135263*
X488772*
X490301Y-135846*
X491611Y-137305*
X509766Y-152763D02*
G01X501032D01*
Y-135263*
X509766*
X506272Y-143721D02*
G01X501032D01*
X575349Y-152763D02*
G01Y-135263D01*
X572729Y-138763*
Y-152763D02*
G01X577969D01*
X588701Y-138180D02*
G01X590011Y-136430D01*
X591539Y-135555*
X593286Y-135263*
X595469Y-135846*
X596997Y-137305*
X597434Y-139054*
X597216Y-140805*
X596342Y-142263*
X591976Y-145180*
X590011Y-147221*
X588701Y-150139*
X588264Y-152763*
X597434*
X606419Y-153346D02*
G01X614279Y-135263D01*
X627849Y-152763D02*
G01Y-135263D01*
X625229Y-138763*
Y-152763D02*
G01X630469D01*
X645349D02*
G01Y-135263D01*
X642729Y-138763*
Y-152763D02*
G01X647969D01*
X658919Y-153346D02*
G01X666779Y-135263D01*
X676201Y-138180D02*
G01X677511Y-136430D01*
X679039Y-135555*
X680786Y-135263*
X682969Y-135846*
X684497Y-137305*
X684934Y-139054*
X684716Y-140805*
X683842Y-142263*
X679476Y-145180*
X677511Y-147221*
X676201Y-150139*
X675764Y-152763*
X684934*
X697849Y-135263D02*
G01X696102Y-135846D01*
X694792Y-137305*
X693919Y-139054*
X693264Y-141388*
X693046Y-144013*
X693264Y-146638*
X693919Y-148972*
X694792Y-150722*
X696102Y-152180*
X697849Y-152763*
X699595Y-152180*
X700906Y-150722*
X701779Y-148972*
X702434Y-146638*
X702652Y-144013*
X702434Y-141388*
X701779Y-139054*
X700906Y-137305*
X699595Y-135846*
X697849Y-135263*
X715349Y-152763D02*
G01Y-135263D01*
X712729Y-138763*
Y-152763D02*
G01X717969D01*
X728046Y-150139D02*
G01X729355Y-151597D01*
X730884Y-152471*
X732849Y-152763*
X734814Y-152180*
X736342Y-151013*
X737434Y-148972*
X737652Y-146638*
X737216Y-144305*
X736124Y-142846*
X734595Y-141680*
X733067Y-141388*
X731539Y-141680*
X729574Y-142846*
X730229Y-135263*
X736124*
X623046Y-107763D02*
G01Y-90263D01*
X627412*
X629159Y-91138*
X630469Y-92305*
X631561Y-94054*
X632434Y-96097*
X632652Y-99013*
X632434Y-101930*
X631561Y-103972*
X630469Y-105722*
X629159Y-106888*
X627412Y-107763*
X623046*
X649279D02*
G01Y-96097D01*
Y-98138D02*
G01X648406Y-96972D01*
X647095Y-96388*
X645567Y-96097*
X644039Y-96680*
X642729Y-97846*
X641855Y-99596*
X641419Y-101930*
X641855Y-104263*
X642729Y-106013*
X644039Y-107180*
X645567Y-107763*
X647095Y-107471*
X648406Y-106597*
X649279Y-105430*
X662849Y-90263D02*
G01Y-107763D01*
X659792Y-96097D02*
G01X665906D01*
X677074Y-99888D02*
G01X684061D01*
X683406Y-97846*
X682314Y-96680*
X680786Y-96097*
X679257Y-96388*
X677947Y-97263*
X677074Y-99305*
X676637Y-101055*
Y-102805*
X677074Y-104555*
X678166Y-106305*
X679476Y-107471*
X681004Y-107763*
X682532Y-107180*
X684061Y-105430*
M02*
